FILE_TYPE = MACRO_DRAWING;
SET COLOR_WIRE YELLOW;
SET COLOR_PROP ORANGE;
SET COLOR_DOT WHITE;
SET COLOR_ARC YELLOW;
SET COLOR_BODY GREEN;
SET COLOR_NOTE PURPLE;
SET PROP_DISPLAY VALUE;
SET PAGE_NUMBER P111;
FORCEADD 9ZXL0451EKILFT..1
(-3375 5000);
FORCEPROP 1 LAST LOCATION U70
J 0
(-3841 6015);
DISPLAY 0.489362 (-3841 6015);
PAINT SKYBLUE (-3841 6015);
FORCEPROP 0 LAST $SEC 1
J 0
(-3775 6425);
DISPLAY 0.680851 (-3775 6425);
PAINT MONO (-3775 6425);
DISPLAY INVISIBLE (-3775 6425);
FORCEPROP 0 LAST CDS_SEC 1
J 0
(-3775 6425);
DISPLAY 1.021277 (-3775 6425);
DISPLAY INVISIBLE (-3775 6425);
FORCEPROP 0 LASTPIN (-4000 4775) $PN 1
J 2
(-4010 4785);
DISPLAY 0.489362 (-4010 4785);
PAINT MONO (-4010 4785);
FORCEPROP 0 LASTPIN (-2750 5475) $PN 32
J 0
(-2740 5485);
DISPLAY 0.489362 (-2740 5485);
PAINT MONO (-2740 5485);
FORCEPROP 0 LASTPIN (-2750 5275) $PN 13
J 0
(-2740 5285);
DISPLAY 0.489362 (-2740 5285);
PAINT MONO (-2740 5285);
FORCEPROP 0 LASTPIN (-2750 5225) $PN 14
J 0
(-2740 5235);
DISPLAY 0.489362 (-2740 5235);
PAINT MONO (-2740 5235);
FORCEPROP 0 LASTPIN (-2750 5175) $PN 19
J 0
(-2740 5185);
DISPLAY 0.489362 (-2740 5185);
PAINT MONO (-2740 5185);
FORCEPROP 0 LASTPIN (-2750 5125) $PN 20
J 0
(-2740 5135);
DISPLAY 0.489362 (-2740 5135);
PAINT MONO (-2740 5135);
FORCEPROP 0 LASTPIN (-2750 5075) $PN 22
J 0
(-2740 5085);
DISPLAY 0.489362 (-2740 5085);
PAINT MONO (-2740 5085);
FORCEPROP 0 LASTPIN (-2750 5025) $PN 23
J 0
(-2740 5035);
DISPLAY 0.489362 (-2740 5035);
PAINT MONO (-2740 5035);
FORCEPROP 0 LASTPIN (-2750 4975) $PN 27
J 0
(-2740 4985);
DISPLAY 0.489362 (-2740 4985);
PAINT MONO (-2740 4985);
FORCEPROP 0 LASTPIN (-2750 4925) $PN 28
J 0
(-2740 4935);
DISPLAY 0.489362 (-2740 4935);
PAINT MONO (-2740 4935);
FORCEPROP 0 LASTPIN (-4000 5175) $PN 3
J 2
(-4010 5185);
DISPLAY 0.489362 (-4010 5185);
PAINT MONO (-4010 5185);
FORCEPROP 0 LASTPIN (-4000 5125) $PN 4
J 2
(-4010 5135);
DISPLAY 0.489362 (-4010 5135);
PAINT MONO (-4010 5135);
FORCEPROP 0 LASTPIN (-2750 4375) $PN 33
J 0
(-2740 4385);
DISPLAY 0.489362 (-2740 4385);
PAINT MONO (-2740 4385);
FORCEPROP 0 LASTPIN (-4000 4725) $PN 9
J 2
(-4010 4735);
DISPLAY 0.489362 (-4010 4735);
PAINT MONO (-4010 4735);
FORCEPROP 0 LASTPIN (-4000 4675) $PN 8
J 2
(-4010 4685);
DISPLAY 0.489362 (-4010 4685);
PAINT MONO (-4010 4685);
FORCEPROP 0 LASTPIN (-4000 4525) $PN 10
J 2
(-4010 4535);
DISPLAY 0.489362 (-4010 4535);
PAINT MONO (-4010 4535);
FORCEPROP 0 LASTPIN (-4000 4475) $PN 11
J 2
(-4010 4485);
DISPLAY 0.489362 (-4010 4485);
PAINT MONO (-4010 4485);
FORCEPROP 0 LASTPIN (-4000 4425) $PN 17
J 2
(-4010 4435);
DISPLAY 0.489362 (-4010 4435);
PAINT MONO (-4010 4435);
FORCEPROP 0 LASTPIN (-4000 4375) $PN 30
J 2
(-4010 4385);
DISPLAY 0.489362 (-4010 4385);
PAINT MONO (-4010 4385);
FORCEPROP 0 LASTPIN (-4000 4875) $PN 7
J 2
(-4010 4885);
DISPLAY 0.489362 (-4010 4885);
PAINT MONO (-4010 4885);
FORCEPROP 0 LASTPIN (-4000 4925) $PN 6
J 2
(-4010 4935);
DISPLAY 0.489362 (-4010 4935);
PAINT MONO (-4010 4935);
FORCEPROP 0 LASTPIN (-4000 5625) $PN 12
J 2
(-4010 5635);
DISPLAY 0.489362 (-4010 5635);
PAINT MONO (-4010 5635);
FORCEPROP 0 LASTPIN (-4000 5575) $PN 16
J 2
(-4010 5585);
DISPLAY 0.489362 (-4010 5585);
PAINT MONO (-4010 5585);
FORCEPROP 0 LASTPIN (-4000 5525) $PN 21
J 2
(-4010 5535);
DISPLAY 0.489362 (-4010 5535);
PAINT MONO (-4010 5535);
FORCEPROP 0 LASTPIN (-4000 5475) $PN 25
J 2
(-4010 5485);
DISPLAY 0.489362 (-4010 5485);
PAINT MONO (-4010 5485);
FORCEPROP 0 LASTPIN (-4000 5425) $PN 29
J 2
(-4010 5435);
DISPLAY 0.489362 (-4010 5435);
PAINT MONO (-4010 5435);
FORCEPROP 0 LASTPIN (-2750 5625) $PN 31
J 0
(-2740 5635);
DISPLAY 0.489362 (-2740 5635);
PAINT MONO (-2740 5635);
FORCEPROP 0 LASTPIN (-4000 5325) $PN 2
J 2
(-4010 5335);
DISPLAY 0.489362 (-4010 5335);
PAINT MONO (-4010 5335);
FORCEPROP 0 LASTPIN (-2750 4725) $PN 15
J 0
(-2740 4735);
DISPLAY 0.489362 (-2740 4735);
PAINT MONO (-2740 4735);
FORCEPROP 0 LASTPIN (-2750 4675) $PN 18
J 0
(-2740 4685);
DISPLAY 0.489362 (-2740 4685);
PAINT MONO (-2740 4685);
FORCEPROP 0 LASTPIN (-2750 4625) $PN 24
J 0
(-2740 4635);
DISPLAY 0.489362 (-2740 4635);
PAINT MONO (-2740 4635);
FORCEPROP 0 LASTPIN (-2750 4575) $PN 26
J 0
(-2740 4585);
DISPLAY 0.489362 (-2740 4585);
PAINT MONO (-2740 4585);
FORCEPROP 0 LASTPIN (-4000 5025) $PN 5
J 2
(-4010 5035);
DISPLAY 0.489362 (-4010 5035);
PAINT MONO (-4010 5035);
FORCEPROP 1 LAST PART_NUMBER AL000451003
J 0
(-3841 5868);
DISPLAY 0.489362 (-3841 5868);
PAINT SKYBLUE (-3841 5868);
FORCEPROP 2 LAST VALUE 9ZXL0451EKILFT
J 0
(-3775 6325);
DISPLAY 0.489362 (-3775 6325);
PAINT SKYBLUE (-3775 6325);
FORCEPROP 1 LAST MATERIAL IC
J 0
(-3841 5741);
DISPLAY 0.489362 (-3841 5741);
PAINT SKYBLUE (-3841 5741);
FORCEPROP 2 LAST PART_TYPE SMLF
J 0
(-3775 6375);
DISPLAY 1.021277 (-3775 6375);
FORCEPROP 1 LAST PATH I1
J 0
(-3375 5000);
DISPLAY 0.723404 (-3375 5000);
PAINT GREEN (-3375 5000);
DISPLAY INVISIBLE (-3375 5000);
FORCEPROP 2 LAST CDS_LIB pure_quanta
J 0
(-3375 5000);
DISPLAY INVISIBLE (-3375 5000);
FORCEPROP 1 LAST CDS_LMAN_SYM_OUTLINE -475,725,475,-725
J 0
(-3375 5000);
DISPLAY 0.468085 (-3375 5000);
PAINT GREEN (-3375 5000);
DISPLAY INVISIBLE (-3375 5000);
FORCEPROP 1 LAST NEEDS_NO_SIZE TRUE
J 0
(-3375 5000);
DISPLAY 0.723404 (-3375 5000);
PAINT GREEN (-3375 5000);
DISPLAY INVISIBLE (-3375 5000);
FORCEADD OFFPAGE..2
(-1025 1225);
FORCEPROP 2 LAST $XR1 110 
J 0
(-716 1225);
DISPLAY 0.638298 (-716 1225);
PAINT MONO (-716 1225);
FORCEPROP 2 LAST $XR0 111 
J 0
(-836 1225);
DISPLAY 0.638298 (-836 1225);
PAINT MONO (-836 1225);
FORCEPROP 1 LAST OFFPAGE TRUE
J 0
(-700 1100);
DISPLAY 0.872340 (-700 1100);
PAINT GREEN (-700 1100);
DISPLAY INVISIBLE (-700 1100);
FORCEPROP 1 LAST COMMENT_BODY TRUE
J 0
(-1070 1130);
DISPLAY 0.872340 (-1070 1130);
PAINT GREEN (-1070 1130);
DISPLAY INVISIBLE (-1070 1130);
FORCEPROP 2 LAST PATH I100
J 0
(-825 1275);
DISPLAY 1.021277 (-825 1275);
DISPLAY INVISIBLE (-825 1275);
FORCEPROP 2 LAST CDS_LIB standard
J 0
(-1025 1225);
DISPLAY INVISIBLE (-1025 1225);
FORCEADD OFFPAGE..3
(-1025 1175);
FORCEPROP 2 LAST $XR1 111 
J 0
(-691 1175);
DISPLAY 0.638298 (-691 1175);
PAINT MONO (-691 1175);
FORCEPROP 2 LAST $XR0 110 
J 0
(-811 1175);
DISPLAY 0.638298 (-811 1175);
PAINT MONO (-811 1175);
FORCEPROP 2 LAST PATH I101
J 0
(-800 1225);
DISPLAY 1.021277 (-800 1225);
DISPLAY INVISIBLE (-800 1225);
FORCEPROP 1 LAST COMMENT_BODY TRUE
J 0
(-1075 1075);
DISPLAY 0.872340 (-1075 1075);
PAINT PEACH (-1075 1075);
DISPLAY INVISIBLE (-1075 1075);
FORCEPROP 1 LAST OFFPAGE TRUE
J 0
(-700 1050);
DISPLAY 0.872340 (-700 1050);
PAINT GREEN (-700 1050);
DISPLAY INVISIBLE (-700 1050);
FORCEPROP 2 LAST CDS_LIB standard
J 0
(-1025 1175);
DISPLAY INVISIBLE (-1025 1175);
FORCEADD OFFPAGE..2
(-1025 1125);
FORCEPROP 2 LAST $XR1 112 
J 0
(-686 1125);
DISPLAY 0.638298 (-686 1125);
PAINT MONO (-686 1125);
FORCEPROP 2 LAST $XR0 111 
J 0
(-806 1125);
DISPLAY 0.638298 (-806 1125);
PAINT MONO (-806 1125);
FORCEPROP 2 LAST PATH I102
J 0
(-825 1175);
DISPLAY 1.021277 (-825 1175);
DISPLAY INVISIBLE (-825 1175);
FORCEPROP 1 LAST COMMENT_BODY TRUE
J 0
(-1070 1030);
DISPLAY 0.872340 (-1070 1030);
PAINT GREEN (-1070 1030);
DISPLAY INVISIBLE (-1070 1030);
FORCEPROP 1 LAST OFFPAGE TRUE
J 0
(-700 1000);
DISPLAY 0.872340 (-700 1000);
PAINT GREEN (-700 1000);
DISPLAY INVISIBLE (-700 1000);
FORCEPROP 2 LAST CDS_LIB standard
J 0
(-1025 1125);
DISPLAY INVISIBLE (-1025 1125);
FORCEADD OFFPAGE..3
(-1025 1075);
FORCEPROP 2 LAST $XR1 112 
J 0
(-691 1075);
DISPLAY 0.638298 (-691 1075);
PAINT MONO (-691 1075);
FORCEPROP 2 LAST $XR0 111 
J 0
(-811 1075);
DISPLAY 0.638298 (-811 1075);
PAINT MONO (-811 1075);
FORCEPROP 2 LAST PATH I103
J 0
(-800 1125);
DISPLAY 1.021277 (-800 1125);
DISPLAY INVISIBLE (-800 1125);
FORCEPROP 1 LAST COMMENT_BODY TRUE
J 0
(-1075 975);
DISPLAY 0.872340 (-1075 975);
PAINT PEACH (-1075 975);
DISPLAY INVISIBLE (-1075 975);
FORCEPROP 1 LAST OFFPAGE TRUE
J 0
(-700 950);
DISPLAY 0.872340 (-700 950);
PAINT GREEN (-700 950);
DISPLAY INVISIBLE (-700 950);
FORCEPROP 2 LAST CDS_LIB standard
J 0
(-1025 1075);
DISPLAY INVISIBLE (-1025 1075);
FORCEADD UNIVERSAL_POWER..1
(-1800 1825);
FORCEPROP 3 LASTPIN (-1800 1775) SIG_NAME P3V3\g
J 0
(-1790 1785);
DISPLAY 0.659574 (-1790 1785);
PAINT MONO (-1790 1785);
DISPLAY INVISIBLE (-1790 1785);
FORCEPROP 1 LAST HDL_POWER P3V3
J 1
(-1800 1875);
DISPLAY 0.489362 (-1800 1875);
PAINT GREEN (-1800 1875);
FORCEPROP 1 LAST PATH I104
J 0
(-1750 1850);
DISPLAY 0.872340 (-1750 1850);
PAINT AQUA (-1750 1850);
DISPLAY INVISIBLE (-1750 1850);
FORCEPROP 2 LAST CDS_LIB pure_quanta_power
J 0
(-1800 1825);
DISPLAY INVISIBLE (-1800 1825);
FORCEADD UNIVERSAL_GND..1
R 2
(-1675 1375);
FORCEPROP 3 LASTPIN (-1675 1425) SIG_NAME GND\g
J 0
(-1665 1435);
DISPLAY 0.659574 (-1665 1435);
PAINT MONO (-1665 1435);
DISPLAY INVISIBLE (-1665 1435);
FORCEPROP 1 LAST HDL_POWER GND
J 1
(-1700 1300);
DISPLAY 0.872340 (-1700 1300);
PAINT GREEN (-1700 1300);
DISPLAY INVISIBLE (-1700 1300);
FORCEPROP 1 LAST PATH I105
J 2
(-1750 1375);
DISPLAY 0.872340 (-1750 1375);
PAINT AQUA (-1750 1375);
DISPLAY INVISIBLE (-1750 1375);
FORCEPROP 2 LAST CDS_LIB pure_quanta_power
J 0
(-1675 1375);
DISPLAY INVISIBLE (-1675 1375);
FORCEADD Q_CAP..1
(-1675 1575);
FORCEPROP 1 LAST LOCATION C32
J 0
(-1625 1675);
DISPLAY 0.489362 (-1625 1675);
PAINT SKYBLUE (-1625 1675);
FORCEPROP 0 LAST $SEC 1
J 0
(-1625 1725);
DISPLAY 0.680851 (-1625 1725);
PAINT MONO (-1625 1725);
DISPLAY INVISIBLE (-1625 1725);
FORCEPROP 0 LAST CDS_SEC 1
J 0
(-1625 1725);
DISPLAY 1.021277 (-1625 1725);
DISPLAY INVISIBLE (-1625 1725);
FORCEPROP 1 LASTPIN (-1675 1675) $PN 1
J 0
(-1665 1655);
DISPLAY 0.489362 (-1665 1655);
PAINT MONO (-1665 1655);
FORCEPROP 1 LASTPIN (-1675 1475) $PN 2
J 0
(-1665 1455);
DISPLAY 0.489362 (-1665 1455);
PAINT MONO (-1665 1455);
FORCEPROP 1 LAST PACK_TYPE 0402
J 0
(-1625 1500);
DISPLAY 0.489362 (-1625 1500);
PAINT SKYBLUE (-1625 1500);
FORCEPROP 1 LAST VOLTAGE 25V
J 0
(-1625 1600);
DISPLAY 0.489362 (-1625 1600);
PAINT SKYBLUE (-1625 1600);
FORCEPROP 1 LAST PART_NUMBER CH4104K1B00
J 0
(-1625 1525);
DISPLAY 0.489362 (-1625 1525);
PAINT SKYBLUE (-1625 1525);
FORCEPROP 1 LAST VALUE 0.1UF
J 0
(-1625 1625);
DISPLAY 0.489362 (-1625 1625);
PAINT SKYBLUE (-1625 1625);
FORCEPROP 1 LAST TOLERANCE 10%
J 0
(-1625 1575);
DISPLAY 0.489362 (-1625 1575);
PAINT SKYBLUE (-1625 1575);
FORCEPROP 1 LAST MATERIAL X7R
J 0
(-1625 1550);
DISPLAY 0.489362 (-1625 1550);
PAINT SKYBLUE (-1625 1550);
FORCEPROP 1 LAST PATH I106
J 0
(-1625 1725);
DISPLAY 0.978723 (-1625 1725);
PAINT WHITE (-1625 1725);
DISPLAY INVISIBLE (-1625 1725);
FORCEPROP 2 LAST CDS_LIB pure_quanta
J 0
(-1675 1575);
DISPLAY INVISIBLE (-1675 1575);
FORCEADD UNIVERSAL_GND..1
R 2
(-1775 775);
FORCEPROP 3 LASTPIN (-1775 825) SIG_NAME GND\g
J 0
(-1765 835);
DISPLAY 0.659574 (-1765 835);
PAINT MONO (-1765 835);
DISPLAY INVISIBLE (-1765 835);
FORCEPROP 1 LAST HDL_POWER GND
J 1
(-1800 700);
DISPLAY 0.702128 (-1800 700);
PAINT GREEN (-1800 700);
DISPLAY INVISIBLE (-1800 700);
FORCEPROP 1 LAST PATH I107
J 2
(-1850 775);
DISPLAY 0.872340 (-1850 775);
PAINT AQUA (-1850 775);
DISPLAY INVISIBLE (-1850 775);
FORCEPROP 2 LAST CDS_LIB pure_quanta_power
J 0
(-1775 775);
DISPLAY INVISIBLE (-1775 775);
FORCEADD UNIVERSAL_GND..1
(-3000 1375);
FORCEPROP 3 LASTPIN (-3000 1425) SIG_NAME GND\g
J 0
(-2990 1435);
DISPLAY 0.659574 (-2990 1435);
PAINT MONO (-2990 1435);
DISPLAY INVISIBLE (-2990 1435);
FORCEPROP 1 LAST HDL_POWER GND
J 1
(-2975 1300);
DISPLAY 0.872340 (-2975 1300);
PAINT GREEN (-2975 1300);
DISPLAY INVISIBLE (-2975 1300);
FORCEPROP 1 LAST PATH I109
J 0
(-2925 1375);
DISPLAY 0.872340 (-2925 1375);
PAINT AQUA (-2925 1375);
DISPLAY INVISIBLE (-2925 1375);
FORCEPROP 2 LAST CDS_LIB pure_quanta_power
J 0
(-3000 1375);
DISPLAY INVISIBLE (-3000 1375);
FORCEADD Q_CAP..1
R 2
(-3000 1575);
FORCEPROP 1 LAST LOCATION C31
J 2
(-3050 1675);
DISPLAY 0.489362 (-3050 1675);
PAINT SKYBLUE (-3050 1675);
FORCEPROP 0 LAST $SEC 1
J 0
(-3050 1725);
DISPLAY 0.680851 (-3050 1725);
PAINT MONO (-3050 1725);
DISPLAY INVISIBLE (-3050 1725);
FORCEPROP 0 LAST CDS_SEC 1
J 0
(-3050 1725);
DISPLAY 1.021277 (-3050 1725);
DISPLAY INVISIBLE (-3050 1725);
FORCEPROP 1 LASTPIN (-3000 1675) $PN 1
J 2
(-3010 1655);
DISPLAY 0.489362 (-3010 1655);
PAINT MONO (-3010 1655);
FORCEPROP 1 LASTPIN (-3000 1475) $PN 2
J 2
(-3010 1455);
DISPLAY 0.489362 (-3010 1455);
PAINT MONO (-3010 1455);
FORCEPROP 1 LAST MATERIAL X7R
J 2
(-3050 1550);
DISPLAY 0.489362 (-3050 1550);
PAINT SKYBLUE (-3050 1550);
FORCEPROP 1 LAST PART_NUMBER CH4104K1B00
J 2
(-3050 1525);
DISPLAY 0.489362 (-3050 1525);
PAINT SKYBLUE (-3050 1525);
FORCEPROP 1 LAST PACK_TYPE 0402
J 2
(-3050 1500);
DISPLAY 0.489362 (-3050 1500);
PAINT SKYBLUE (-3050 1500);
FORCEPROP 1 LAST VOLTAGE 25V
J 2
(-3050 1600);
DISPLAY 0.489362 (-3050 1600);
PAINT SKYBLUE (-3050 1600);
FORCEPROP 1 LAST VALUE 0.1UF
J 2
(-3050 1625);
DISPLAY 0.489362 (-3050 1625);
PAINT SKYBLUE (-3050 1625);
FORCEPROP 1 LAST TOLERANCE 10%
J 2
(-3050 1575);
DISPLAY 0.489362 (-3050 1575);
PAINT SKYBLUE (-3050 1575);
FORCEPROP 1 LAST PATH I110
J 2
(-3050 1725);
DISPLAY 0.978723 (-3050 1725);
PAINT WHITE (-3050 1725);
DISPLAY INVISIBLE (-3050 1725);
FORCEPROP 2 LAST CDS_LIB pure_quanta
J 0
(-3000 1575);
DISPLAY INVISIBLE (-3000 1575);
FORCEADD LSF0204DRUTR..1
(-2350 1150);
FORCEPROP 1 LAST LOCATION U4
J 0
(-2582 1558);
DISPLAY 0.489362 (-2582 1558);
PAINT SKYBLUE (-2582 1558);
FORCEPROP 0 LAST $SEC 1
J 0
(-2575 1700);
DISPLAY 0.680851 (-2575 1700);
PAINT MONO (-2575 1700);
DISPLAY INVISIBLE (-2575 1700);
FORCEPROP 0 LAST CDS_SEC 1
J 0
(-2575 1700);
DISPLAY 1.021277 (-2575 1700);
DISPLAY INVISIBLE (-2575 1700);
FORCEPROP 0 LASTPIN (-2725 1225) $PN 2
J 2
(-2735 1235);
DISPLAY 0.489362 (-2735 1235);
PAINT MONO (-2735 1235);
FORCEPROP 0 LASTPIN (-2725 1175) $PN 3
J 2
(-2735 1185);
DISPLAY 0.489362 (-2735 1185);
PAINT MONO (-2735 1185);
FORCEPROP 0 LASTPIN (-2725 1125) $PN 4
J 2
(-2735 1135);
DISPLAY 0.489362 (-2735 1135);
PAINT MONO (-2735 1135);
FORCEPROP 0 LASTPIN (-2725 1075) $PN 5
J 2
(-2735 1085);
DISPLAY 0.489362 (-2735 1085);
PAINT MONO (-2735 1085);
FORCEPROP 0 LASTPIN (-1975 1225) $PN 10
J 0
(-1965 1235);
DISPLAY 0.489362 (-1965 1235);
PAINT MONO (-1965 1235);
FORCEPROP 0 LASTPIN (-1975 1175) $PN 9
J 0
(-1965 1185);
DISPLAY 0.489362 (-1965 1185);
PAINT MONO (-1965 1185);
FORCEPROP 0 LASTPIN (-1975 1125) $PN 8
J 0
(-1965 1135);
DISPLAY 0.489362 (-1965 1135);
PAINT MONO (-1965 1135);
FORCEPROP 0 LASTPIN (-1975 1075) $PN 7
J 0
(-1965 1085);
DISPLAY 0.489362 (-1965 1085);
PAINT MONO (-1965 1085);
FORCEPROP 0 LASTPIN (-2725 975) $PN 12
J 2
(-2735 985);
DISPLAY 0.489362 (-2735 985);
PAINT MONO (-2735 985);
FORCEPROP 0 LASTPIN (-1975 975) $PN 6
J 0
(-1965 985);
DISPLAY 0.489362 (-1965 985);
PAINT MONO (-1965 985);
FORCEPROP 0 LASTPIN (-2725 1325) $PN 1
J 2
(-2735 1335);
DISPLAY 0.489362 (-2735 1335);
PAINT MONO (-2735 1335);
FORCEPROP 0 LASTPIN (-1975 1325) $PN 11
J 0
(-1965 1335);
DISPLAY 0.489362 (-1965 1335);
PAINT MONO (-1965 1335);
FORCEPROP 1 LAST PART_NUMBER AL000204002
J 0
(-2582 1466);
DISPLAY 0.489362 (-2582 1466);
PAINT SKYBLUE (-2582 1466);
FORCEPROP 2 LAST VALUE LSF0204DRUTR
J 0
(-2575 1600);
DISPLAY 0.489362 (-2575 1600);
PAINT SKYBLUE (-2575 1600);
FORCEPROP 1 LAST MATERIAL IC
J 0
(-2582 1382);
DISPLAY 0.489362 (-2582 1382);
PAINT SKYBLUE (-2582 1382);
FORCEPROP 2 LAST PART_TYPE SMLF
J 0
(-2575 1650);
DISPLAY 1.021277 (-2575 1650);
FORCEPROP 1 LAST PATH I111
J 0
(-2125 925);
DISPLAY 0.723404 (-2125 925);
PAINT GREEN (-2125 925);
DISPLAY INVISIBLE (-2125 925);
FORCEPROP 2 LAST CDS_LIB pure_quanta
J 0
(-2350 1150);
DISPLAY INVISIBLE (-2350 1150);
FORCEPROP 1 LAST CDS_LMAN_SYM_OUTLINE -225,225,225,-225
J 0
(-2350 1150);
DISPLAY 0.468085 (-2350 1150);
PAINT GREEN (-2350 1150);
DISPLAY INVISIBLE (-2350 1150);
FORCEPROP 1 LAST NEEDS_NO_SIZE TRUE
J 0
(-2125 982);
DISPLAY 0.723404 (-2125 982);
PAINT GREEN (-2125 982);
DISPLAY INVISIBLE (-2125 982);
FORCEADD OFFPAGE..1
(-3675 1225);
FORCEPROP 2 LAST $XR1 111 
J 0
(-4016 1225);
DISPLAY 0.638298 (-4016 1225);
PAINT MONO (-4016 1225);
FORCEPROP 2 LAST $XR0 28 
J 0
(-3896 1225);
DISPLAY 0.638298 (-3896 1225);
PAINT MONO (-3896 1225);
FORCEPROP 2 LAST PATH I112
J 0
(-3875 1275);
DISPLAY 1.021277 (-3875 1275);
DISPLAY INVISIBLE (-3875 1275);
FORCEPROP 1 LAST COMMENT_BODY TRUE
J 0
(-3545 1125);
DISPLAY 1.106383 (-3545 1125);
PAINT PEACH (-3545 1125);
DISPLAY INVISIBLE (-3545 1125);
FORCEPROP 1 LAST OFFPAGE TRUE
J 0
(-3345 1095);
PAINT GREEN (-3345 1095);
DISPLAY INVISIBLE (-3345 1095);
FORCEPROP 2 LAST CDS_LIB standard
J 0
(-3675 1225);
DISPLAY INVISIBLE (-3675 1225);
FORCEADD OFFPAGE..3
R 2
(-3675 1175);
FORCEPROP 2 LAST $XR1 111 
J 0
(-4044 1175);
DISPLAY 0.638298 (-4044 1175);
PAINT MONO (-4044 1175);
FORCEPROP 2 LAST $XR0 28 
J 0
(-3924 1175);
DISPLAY 0.638298 (-3924 1175);
PAINT MONO (-3924 1175);
FORCEPROP 2 LAST PATH I113
J 0
(-3900 1225);
DISPLAY 1.021277 (-3900 1225);
DISPLAY INVISIBLE (-3900 1225);
FORCEPROP 1 LAST COMMENT_BODY TRUE
J 2
(-3625 1075);
DISPLAY 0.872340 (-3625 1075);
PAINT PEACH (-3625 1075);
DISPLAY INVISIBLE (-3625 1075);
FORCEPROP 1 LAST OFFPAGE TRUE
J 2
(-4000 1050);
DISPLAY 0.872340 (-4000 1050);
PAINT GREEN (-4000 1050);
DISPLAY INVISIBLE (-4000 1050);
FORCEPROP 2 LAST CDS_LIB standard
J 0
(-3675 1175);
DISPLAY INVISIBLE (-3675 1175);
FORCEADD OFFPAGE..1
(-3675 1125);
FORCEPROP 2 LAST $XR1 111 
J 0
(-4046 1125);
DISPLAY 0.638298 (-4046 1125);
PAINT MONO (-4046 1125);
FORCEPROP 2 LAST $XR0 28 
J 0
(-3926 1125);
DISPLAY 0.638298 (-3926 1125);
PAINT MONO (-3926 1125);
FORCEPROP 2 LAST PATH I114
J 0
(-3925 1175);
DISPLAY 1.021277 (-3925 1175);
DISPLAY INVISIBLE (-3925 1175);
FORCEPROP 1 LAST COMMENT_BODY TRUE
J 0
(-3545 1025);
DISPLAY 1.106383 (-3545 1025);
PAINT PEACH (-3545 1025);
DISPLAY INVISIBLE (-3545 1025);
FORCEPROP 1 LAST OFFPAGE TRUE
J 0
(-3345 995);
PAINT GREEN (-3345 995);
DISPLAY INVISIBLE (-3345 995);
FORCEPROP 2 LAST CDS_LIB standard
J 0
(-3675 1125);
DISPLAY INVISIBLE (-3675 1125);
FORCEADD OFFPAGE..3
R 2
(-3675 1075);
FORCEPROP 2 LAST $XR1 111 
J 0
(-4044 1075);
DISPLAY 0.638298 (-4044 1075);
PAINT MONO (-4044 1075);
FORCEPROP 2 LAST $XR0 28 
J 0
(-3924 1075);
DISPLAY 0.638298 (-3924 1075);
PAINT MONO (-3924 1075);
FORCEPROP 2 LAST PATH I115
J 0
(-3900 1125);
DISPLAY 1.021277 (-3900 1125);
DISPLAY INVISIBLE (-3900 1125);
FORCEPROP 1 LAST COMMENT_BODY TRUE
J 2
(-3625 975);
DISPLAY 0.872340 (-3625 975);
PAINT PEACH (-3625 975);
DISPLAY INVISIBLE (-3625 975);
FORCEPROP 1 LAST OFFPAGE TRUE
J 2
(-4000 950);
DISPLAY 0.872340 (-4000 950);
PAINT GREEN (-4000 950);
DISPLAY INVISIBLE (-4000 950);
FORCEPROP 2 LAST CDS_LIB standard
J 0
(-3675 1075);
DISPLAY INVISIBLE (-3675 1075);
FORCEADD UNIVERSAL_POWER..1
(-1750 2550);
FORCEPROP 3 LASTPIN (-1750 2500) SIG_NAME P3V3\g
J 0
(-1740 2510);
DISPLAY 0.659574 (-1740 2510);
PAINT MONO (-1740 2510);
DISPLAY INVISIBLE (-1740 2510);
FORCEPROP 1 LAST HDL_POWER P3V3
J 1
(-1750 2600);
DISPLAY 0.489362 (-1750 2600);
PAINT GREEN (-1750 2600);
FORCEPROP 1 LAST PATH I139
J 0
(-1700 2575);
DISPLAY 0.872340 (-1700 2575);
PAINT AQUA (-1700 2575);
DISPLAY INVISIBLE (-1700 2575);
FORCEPROP 2 LAST CDS_LIB pure_quanta_power
J 0
(-1750 2550);
DISPLAY INVISIBLE (-1750 2550);
FORCEADD Q_RES..1
(-1525 2300);
FORCEPROP 1 LAST LOCATION R52
J 0
(-1725 2300);
DISPLAY 0.489362 (-1725 2300);
PAINT SKYBLUE (-1725 2300);
FORCEPROP 0 LAST $SEC 1
J 0
(-1600 2375);
DISPLAY 0.680851 (-1600 2375);
PAINT MONO (-1600 2375);
DISPLAY INVISIBLE (-1600 2375);
FORCEPROP 0 LAST CDS_SEC 1
J 0
(-1600 2375);
DISPLAY 1.021277 (-1600 2375);
DISPLAY INVISIBLE (-1600 2375);
FORCEPROP 1 LASTPIN (-1625 2300) $PN 1
J 0
(-1613 2312);
DISPLAY 0.489362 (-1613 2312);
PAINT MONO (-1613 2312);
FORCEPROP 1 LASTPIN (-1425 2300) $PN 2
J 0
(-1463 2312);
DISPLAY 0.489362 (-1463 2312);
PAINT MONO (-1463 2312);
FORCEPROP 1 LAST VALUE 4.7K
J 0
(-1400 2300);
DISPLAY 0.489362 (-1400 2300);
PAINT SKYBLUE (-1400 2300);
FORCEPROP 1 LAST PACK_TYPE 0402LF
J 0
(-1275 2150);
DISPLAY 0.510638 (-1275 2150);
PAINT SKYBLUE (-1275 2150);
DISPLAY INVISIBLE (-1275 2150);
FORCEPROP 1 LAST PART_NUMBER TMP_QCS24702JB38
J 0
(-1575 2400);
DISPLAY 0.510638 (-1575 2400);
PAINT SKYBLUE (-1575 2400);
DISPLAY INVISIBLE (-1575 2400);
FORCEPROP 1 LAST TOLERANCE 5%
J 0
(-1400 2300);
DISPLAY 0.510638 (-1400 2300);
PAINT SKYBLUE (-1400 2300);
DISPLAY INVISIBLE (-1400 2300);
FORCEPROP 1 LAST MATERIAL CHIP
J 0
(-1425 2275);
DISPLAY 0.489362 (-1425 2275);
PAINT SKYBLUE (-1425 2275);
DISPLAY INVISIBLE (-1425 2275);
FORCEPROP 1 LAST WATTAGE 1/16W
J 2
(-1550 2150);
DISPLAY 0.510638 (-1550 2150);
PAINT SKYBLUE (-1550 2150);
DISPLAY INVISIBLE (-1550 2150);
FORCEPROP 1 LAST PATH I140
J 0
(-1575 2450);
DISPLAY 0.978723 (-1575 2450);
PAINT WHITE (-1575 2450);
DISPLAY INVISIBLE (-1575 2450);
FORCEPROP 2 LAST CDS_LIB pure_quanta
J 0
(-1525 2300);
DISPLAY INVISIBLE (-1525 2300);
FORCEADD Q_RES..1
(-1525 2250);
FORCEPROP 1 LAST LOCATION R53
J 0
(-1725 2250);
DISPLAY 0.489362 (-1725 2250);
PAINT SKYBLUE (-1725 2250);
FORCEPROP 0 LAST $SEC 1
J 0
(-1600 2325);
DISPLAY 0.680851 (-1600 2325);
PAINT MONO (-1600 2325);
DISPLAY INVISIBLE (-1600 2325);
FORCEPROP 0 LAST CDS_SEC 1
J 0
(-1600 2325);
DISPLAY 1.021277 (-1600 2325);
DISPLAY INVISIBLE (-1600 2325);
FORCEPROP 1 LASTPIN (-1625 2250) $PN 1
J 0
(-1613 2262);
DISPLAY 0.489362 (-1613 2262);
PAINT MONO (-1613 2262);
FORCEPROP 1 LASTPIN (-1425 2250) $PN 2
J 0
(-1463 2262);
DISPLAY 0.489362 (-1463 2262);
PAINT MONO (-1463 2262);
FORCEPROP 1 LAST VALUE 4.7K
J 0
(-1400 2250);
DISPLAY 0.489362 (-1400 2250);
PAINT SKYBLUE (-1400 2250);
FORCEPROP 1 LAST PACK_TYPE 0402LF
J 0
(-1275 2100);
DISPLAY 0.510638 (-1275 2100);
PAINT SKYBLUE (-1275 2100);
DISPLAY INVISIBLE (-1275 2100);
FORCEPROP 1 LAST PART_NUMBER TMP_QCS24702JB38
J 0
(-1575 2350);
DISPLAY 0.510638 (-1575 2350);
PAINT SKYBLUE (-1575 2350);
DISPLAY INVISIBLE (-1575 2350);
FORCEPROP 1 LAST TOLERANCE 5%
J 0
(-1400 2250);
DISPLAY 0.510638 (-1400 2250);
PAINT SKYBLUE (-1400 2250);
DISPLAY INVISIBLE (-1400 2250);
FORCEPROP 1 LAST MATERIAL CHIP
J 0
(-1425 2225);
DISPLAY 0.489362 (-1425 2225);
PAINT SKYBLUE (-1425 2225);
DISPLAY INVISIBLE (-1425 2225);
FORCEPROP 1 LAST WATTAGE 1/16W
J 2
(-1550 2100);
DISPLAY 0.510638 (-1550 2100);
PAINT SKYBLUE (-1550 2100);
DISPLAY INVISIBLE (-1550 2100);
FORCEPROP 1 LAST PATH I141
J 0
(-1575 2400);
DISPLAY 0.978723 (-1575 2400);
PAINT WHITE (-1575 2400);
DISPLAY INVISIBLE (-1575 2400);
FORCEPROP 2 LAST CDS_LIB pure_quanta
J 0
(-1525 2250);
DISPLAY INVISIBLE (-1525 2250);
FORCEADD Q_RES..1
(-1525 2150);
FORCEPROP 1 LAST LOCATION R55
J 0
(-1725 2150);
DISPLAY 0.489362 (-1725 2150);
PAINT SKYBLUE (-1725 2150);
FORCEPROP 0 LAST $SEC 1
J 0
(-1600 2225);
DISPLAY 0.680851 (-1600 2225);
PAINT MONO (-1600 2225);
DISPLAY INVISIBLE (-1600 2225);
FORCEPROP 0 LAST CDS_SEC 1
J 0
(-1600 2225);
DISPLAY 1.021277 (-1600 2225);
DISPLAY INVISIBLE (-1600 2225);
FORCEPROP 1 LASTPIN (-1625 2150) $PN 1
J 0
(-1613 2162);
DISPLAY 0.489362 (-1613 2162);
PAINT MONO (-1613 2162);
FORCEPROP 1 LASTPIN (-1425 2150) $PN 2
J 0
(-1463 2162);
DISPLAY 0.489362 (-1463 2162);
PAINT MONO (-1463 2162);
FORCEPROP 1 LAST VALUE 4.7K
J 0
(-1400 2150);
DISPLAY 0.489362 (-1400 2150);
PAINT SKYBLUE (-1400 2150);
FORCEPROP 1 LAST PACK_TYPE 0402LF
J 0
(-1275 2000);
DISPLAY 0.510638 (-1275 2000);
PAINT SKYBLUE (-1275 2000);
DISPLAY INVISIBLE (-1275 2000);
FORCEPROP 1 LAST PART_NUMBER TMP_QCS24702JB38
J 0
(-1575 2250);
DISPLAY 0.510638 (-1575 2250);
PAINT SKYBLUE (-1575 2250);
DISPLAY INVISIBLE (-1575 2250);
FORCEPROP 1 LAST TOLERANCE 5%
J 0
(-1400 2150);
DISPLAY 0.510638 (-1400 2150);
PAINT SKYBLUE (-1400 2150);
DISPLAY INVISIBLE (-1400 2150);
FORCEPROP 1 LAST MATERIAL CHIP
J 0
(-1425 2125);
DISPLAY 0.489362 (-1425 2125);
PAINT SKYBLUE (-1425 2125);
DISPLAY INVISIBLE (-1425 2125);
FORCEPROP 1 LAST WATTAGE 1/16W
J 2
(-1550 2000);
DISPLAY 0.510638 (-1550 2000);
PAINT SKYBLUE (-1550 2000);
DISPLAY INVISIBLE (-1550 2000);
FORCEPROP 1 LAST PATH I142
J 0
(-1575 2300);
DISPLAY 0.978723 (-1575 2300);
PAINT WHITE (-1575 2300);
DISPLAY INVISIBLE (-1575 2300);
FORCEPROP 2 LAST CDS_LIB pure_quanta
J 0
(-1525 2150);
DISPLAY INVISIBLE (-1525 2150);
FORCEADD Q_RES..1
(-1525 2200);
FORCEPROP 1 LAST LOCATION R54
J 0
(-1725 2200);
DISPLAY 0.489362 (-1725 2200);
PAINT SKYBLUE (-1725 2200);
FORCEPROP 0 LAST $SEC 1
J 0
(-1600 2275);
DISPLAY 0.680851 (-1600 2275);
PAINT MONO (-1600 2275);
DISPLAY INVISIBLE (-1600 2275);
FORCEPROP 0 LAST CDS_SEC 1
J 0
(-1600 2275);
DISPLAY 1.021277 (-1600 2275);
DISPLAY INVISIBLE (-1600 2275);
FORCEPROP 1 LASTPIN (-1625 2200) $PN 1
J 0
(-1613 2212);
DISPLAY 0.489362 (-1613 2212);
PAINT MONO (-1613 2212);
FORCEPROP 1 LASTPIN (-1425 2200) $PN 2
J 0
(-1463 2212);
DISPLAY 0.489362 (-1463 2212);
PAINT MONO (-1463 2212);
FORCEPROP 1 LAST VALUE 4.7K
J 0
(-1400 2200);
DISPLAY 0.489362 (-1400 2200);
PAINT SKYBLUE (-1400 2200);
FORCEPROP 1 LAST PACK_TYPE 0402LF
J 0
(-1275 2050);
DISPLAY 0.510638 (-1275 2050);
PAINT SKYBLUE (-1275 2050);
DISPLAY INVISIBLE (-1275 2050);
FORCEPROP 1 LAST PART_NUMBER TMP_QCS24702JB38
J 0
(-1575 2300);
DISPLAY 0.510638 (-1575 2300);
PAINT SKYBLUE (-1575 2300);
DISPLAY INVISIBLE (-1575 2300);
FORCEPROP 1 LAST TOLERANCE 5%
J 0
(-1400 2200);
DISPLAY 0.510638 (-1400 2200);
PAINT SKYBLUE (-1400 2200);
DISPLAY INVISIBLE (-1400 2200);
FORCEPROP 1 LAST MATERIAL CHIP
J 0
(-1425 2175);
DISPLAY 0.489362 (-1425 2175);
PAINT SKYBLUE (-1425 2175);
DISPLAY INVISIBLE (-1425 2175);
FORCEPROP 1 LAST WATTAGE 1/16W
J 2
(-1550 2050);
DISPLAY 0.510638 (-1550 2050);
PAINT SKYBLUE (-1550 2050);
DISPLAY INVISIBLE (-1550 2050);
FORCEPROP 1 LAST PATH I143
J 0
(-1575 2350);
DISPLAY 0.978723 (-1575 2350);
PAINT WHITE (-1575 2350);
DISPLAY INVISIBLE (-1575 2350);
FORCEPROP 2 LAST CDS_LIB pure_quanta
J 0
(-1525 2200);
DISPLAY INVISIBLE (-1525 2200);
FORCEADD OFFPAGE..2
(-700 2150);
FORCEPROP 2 LAST $XR1 112 
J 0
(-391 2150);
DISPLAY 0.638298 (-391 2150);
PAINT MONO (-391 2150);
FORCEPROP 2 LAST $XR0 111 
J 0
(-511 2150);
DISPLAY 0.638298 (-511 2150);
PAINT MONO (-511 2150);
FORCEPROP 2 LAST PATH I144
J 0
(-525 2225);
DISPLAY 1.021277 (-525 2225);
DISPLAY INVISIBLE (-525 2225);
FORCEPROP 1 LAST COMMENT_BODY TRUE
J 0
(-745 2055);
DISPLAY 0.872340 (-745 2055);
PAINT PEACH (-745 2055);
DISPLAY INVISIBLE (-745 2055);
FORCEPROP 1 LAST OFFPAGE TRUE
J 0
(-375 2025);
DISPLAY 0.872340 (-375 2025);
PAINT GREEN (-375 2025);
DISPLAY INVISIBLE (-375 2025);
FORCEPROP 2 LAST CDS_LIB standard
J 0
(-700 2150);
DISPLAY INVISIBLE (-700 2150);
FORCEADD OFFPAGE..2
(-700 2300);
FORCEPROP 2 LAST $XR1 110 
J 0
(-391 2300);
DISPLAY 0.638298 (-391 2300);
PAINT MONO (-391 2300);
FORCEPROP 2 LAST $XR0 111 
J 0
(-511 2300);
DISPLAY 0.638298 (-511 2300);
PAINT MONO (-511 2300);
FORCEPROP 2 LAST PATH I145
J 0
(-525 2375);
DISPLAY 1.021277 (-525 2375);
DISPLAY INVISIBLE (-525 2375);
FORCEPROP 1 LAST COMMENT_BODY TRUE
J 0
(-745 2205);
DISPLAY 0.872340 (-745 2205);
PAINT PEACH (-745 2205);
DISPLAY INVISIBLE (-745 2205);
FORCEPROP 1 LAST OFFPAGE TRUE
J 0
(-375 2175);
DISPLAY 0.872340 (-375 2175);
PAINT GREEN (-375 2175);
DISPLAY INVISIBLE (-375 2175);
FORCEPROP 2 LAST CDS_LIB standard
J 0
(-700 2300);
DISPLAY INVISIBLE (-700 2300);
FORCEADD OFFPAGE..2
(-700 2250);
FORCEPROP 2 LAST $XR1 111 
J 0
(-391 2250);
DISPLAY 0.638298 (-391 2250);
PAINT MONO (-391 2250);
FORCEPROP 2 LAST $XR0 110 
J 0
(-511 2250);
DISPLAY 0.638298 (-511 2250);
PAINT MONO (-511 2250);
FORCEPROP 2 LAST PATH I146
J 0
(-525 2325);
DISPLAY 1.021277 (-525 2325);
DISPLAY INVISIBLE (-525 2325);
FORCEPROP 1 LAST COMMENT_BODY TRUE
J 0
(-745 2155);
DISPLAY 0.872340 (-745 2155);
PAINT PEACH (-745 2155);
DISPLAY INVISIBLE (-745 2155);
FORCEPROP 1 LAST OFFPAGE TRUE
J 0
(-375 2125);
DISPLAY 0.872340 (-375 2125);
PAINT GREEN (-375 2125);
DISPLAY INVISIBLE (-375 2125);
FORCEPROP 2 LAST CDS_LIB standard
J 0
(-700 2250);
DISPLAY INVISIBLE (-700 2250);
FORCEADD OFFPAGE..2
(-700 2200);
FORCEPROP 2 LAST $XR1 112 
J 0
(-391 2200);
DISPLAY 0.638298 (-391 2200);
PAINT MONO (-391 2200);
FORCEPROP 2 LAST $XR0 111 
J 0
(-511 2200);
DISPLAY 0.638298 (-511 2200);
PAINT MONO (-511 2200);
FORCEPROP 2 LAST PATH I147
J 0
(-525 2275);
DISPLAY 1.021277 (-525 2275);
DISPLAY INVISIBLE (-525 2275);
FORCEPROP 1 LAST COMMENT_BODY TRUE
J 0
(-745 2105);
DISPLAY 0.872340 (-745 2105);
PAINT PEACH (-745 2105);
DISPLAY INVISIBLE (-745 2105);
FORCEPROP 1 LAST OFFPAGE TRUE
J 0
(-375 2075);
DISPLAY 0.872340 (-375 2075);
PAINT GREEN (-375 2075);
DISPLAY INVISIBLE (-375 2075);
FORCEPROP 2 LAST CDS_LIB standard
J 0
(-700 2200);
DISPLAY INVISIBLE (-700 2200);
FORCEADD OFFPAGE..2
(-825 2850);
FORCEPROP 2 LAST $XR1 111 
J 0
(-546 2850);
DISPLAY 0.638298 (-546 2850);
PAINT MONO (-546 2850);
FORCEPROP 2 LAST $XR0 28 
J 0
(-636 2850);
DISPLAY 0.638298 (-636 2850);
PAINT MONO (-636 2850);
FORCEPROP 2 LAST PATH I148
J 0
(-525 2900);
DISPLAY 1.021277 (-525 2900);
DISPLAY INVISIBLE (-525 2900);
FORCEPROP 1 LAST COMMENT_BODY TRUE
J 0
(-870 2755);
DISPLAY 0.872340 (-870 2755);
PAINT PEACH (-870 2755);
DISPLAY INVISIBLE (-870 2755);
FORCEPROP 1 LAST OFFPAGE TRUE
J 0
(-500 2725);
DISPLAY 0.872340 (-500 2725);
PAINT GREEN (-500 2725);
DISPLAY INVISIBLE (-500 2725);
FORCEPROP 2 LAST CDS_LIB standard
J 0
(-825 2850);
DISPLAY INVISIBLE (-825 2850);
FORCEADD OFFPAGE..2
(-825 2800);
FORCEPROP 2 LAST $XR1 111 
J 0
(-546 2800);
DISPLAY 0.638298 (-546 2800);
PAINT MONO (-546 2800);
FORCEPROP 2 LAST $XR0 28 
J 0
(-636 2800);
DISPLAY 0.638298 (-636 2800);
PAINT MONO (-636 2800);
FORCEPROP 2 LAST PATH I149
J 0
(-525 2850);
DISPLAY 1.021277 (-525 2850);
DISPLAY INVISIBLE (-525 2850);
FORCEPROP 1 LAST COMMENT_BODY TRUE
J 0
(-870 2705);
DISPLAY 0.872340 (-870 2705);
PAINT PEACH (-870 2705);
DISPLAY INVISIBLE (-870 2705);
FORCEPROP 1 LAST OFFPAGE TRUE
J 0
(-500 2675);
DISPLAY 0.872340 (-500 2675);
PAINT GREEN (-500 2675);
DISPLAY INVISIBLE (-500 2675);
FORCEPROP 2 LAST CDS_LIB standard
J 0
(-825 2800);
DISPLAY INVISIBLE (-825 2800);
FORCEADD OFFPAGE..2
(-825 2900);
FORCEPROP 2 LAST $XR1 111 
J 0
(-546 2900);
DISPLAY 0.638298 (-546 2900);
PAINT MONO (-546 2900);
FORCEPROP 2 LAST $XR0 28 
J 0
(-636 2900);
DISPLAY 0.638298 (-636 2900);
PAINT MONO (-636 2900);
FORCEPROP 2 LAST PATH I150
J 0
(-525 2950);
DISPLAY 1.021277 (-525 2950);
DISPLAY INVISIBLE (-525 2950);
FORCEPROP 1 LAST COMMENT_BODY TRUE
J 0
(-870 2805);
DISPLAY 0.872340 (-870 2805);
PAINT PEACH (-870 2805);
DISPLAY INVISIBLE (-870 2805);
FORCEPROP 1 LAST OFFPAGE TRUE
J 0
(-500 2775);
DISPLAY 0.872340 (-500 2775);
PAINT GREEN (-500 2775);
DISPLAY INVISIBLE (-500 2775);
FORCEPROP 2 LAST CDS_LIB standard
J 0
(-825 2900);
DISPLAY INVISIBLE (-825 2900);
FORCEADD OFFPAGE..2
(-825 2750);
FORCEPROP 2 LAST $XR1 111 
J 0
(-546 2750);
DISPLAY 0.638298 (-546 2750);
PAINT MONO (-546 2750);
FORCEPROP 2 LAST $XR0 28 
J 0
(-636 2750);
DISPLAY 0.638298 (-636 2750);
PAINT MONO (-636 2750);
FORCEPROP 2 LAST PATH I151
J 0
(-525 2800);
DISPLAY 1.021277 (-525 2800);
DISPLAY INVISIBLE (-525 2800);
FORCEPROP 1 LAST COMMENT_BODY TRUE
J 0
(-870 2655);
DISPLAY 0.872340 (-870 2655);
PAINT PEACH (-870 2655);
DISPLAY INVISIBLE (-870 2655);
FORCEPROP 1 LAST OFFPAGE TRUE
J 0
(-500 2625);
DISPLAY 0.872340 (-500 2625);
PAINT GREEN (-500 2625);
DISPLAY INVISIBLE (-500 2625);
FORCEPROP 2 LAST CDS_LIB standard
J 0
(-825 2750);
DISPLAY INVISIBLE (-825 2750);
FORCEADD Q_RES..1
(-1575 2800);
FORCEPROP 1 LAST LOCATION R44
J 0
(-1750 2800);
DISPLAY 0.489362 (-1750 2800);
PAINT SKYBLUE (-1750 2800);
FORCEPROP 0 LAST $SEC 1
J 0
(-1675 2875);
DISPLAY 0.680851 (-1675 2875);
PAINT MONO (-1675 2875);
DISPLAY INVISIBLE (-1675 2875);
FORCEPROP 0 LAST CDS_SEC 1
J 0
(-1675 2875);
DISPLAY 1.021277 (-1675 2875);
DISPLAY INVISIBLE (-1675 2875);
FORCEPROP 1 LASTPIN (-1675 2800) $PN 1
J 0
(-1663 2812);
DISPLAY 0.489362 (-1663 2812);
PAINT MONO (-1663 2812);
FORCEPROP 1 LASTPIN (-1475 2800) $PN 2
J 0
(-1513 2812);
DISPLAY 0.489362 (-1513 2812);
PAINT MONO (-1513 2812);
FORCEPROP 1 LAST VALUE 4.7K
J 0
(-1450 2800);
DISPLAY 0.489362 (-1450 2800);
PAINT SKYBLUE (-1450 2800);
FORCEPROP 1 LAST PACK_TYPE 0402LF
J 0
(-1325 2650);
DISPLAY 0.510638 (-1325 2650);
PAINT SKYBLUE (-1325 2650);
DISPLAY INVISIBLE (-1325 2650);
FORCEPROP 1 LAST PART_NUMBER TMP_QCS24702JB38
J 0
(-1625 2900);
DISPLAY 0.510638 (-1625 2900);
PAINT SKYBLUE (-1625 2900);
DISPLAY INVISIBLE (-1625 2900);
FORCEPROP 1 LAST TOLERANCE 5%
J 0
(-1450 2800);
DISPLAY 0.510638 (-1450 2800);
PAINT SKYBLUE (-1450 2800);
DISPLAY INVISIBLE (-1450 2800);
FORCEPROP 1 LAST MATERIAL CHIP
J 0
(-1475 2775);
DISPLAY 0.489362 (-1475 2775);
PAINT SKYBLUE (-1475 2775);
DISPLAY INVISIBLE (-1475 2775);
FORCEPROP 1 LAST WATTAGE 1/16W
J 2
(-1600 2650);
DISPLAY 0.510638 (-1600 2650);
PAINT SKYBLUE (-1600 2650);
DISPLAY INVISIBLE (-1600 2650);
FORCEPROP 1 LAST PATH I152
J 0
(-1625 2950);
DISPLAY 0.978723 (-1625 2950);
PAINT WHITE (-1625 2950);
DISPLAY INVISIBLE (-1625 2950);
FORCEPROP 2 LAST CDS_LIB pure_quanta
J 0
(-1575 2800);
DISPLAY INVISIBLE (-1575 2800);
FORCEADD Q_RES..1
(-1575 2850);
FORCEPROP 1 LAST LOCATION R43
J 0
(-1750 2850);
DISPLAY 0.489362 (-1750 2850);
PAINT SKYBLUE (-1750 2850);
FORCEPROP 0 LAST $SEC 1
J 0
(-1675 2925);
DISPLAY 0.680851 (-1675 2925);
PAINT MONO (-1675 2925);
DISPLAY INVISIBLE (-1675 2925);
FORCEPROP 0 LAST CDS_SEC 1
J 0
(-1675 2925);
DISPLAY 1.021277 (-1675 2925);
DISPLAY INVISIBLE (-1675 2925);
FORCEPROP 1 LASTPIN (-1675 2850) $PN 1
J 0
(-1663 2862);
DISPLAY 0.489362 (-1663 2862);
PAINT MONO (-1663 2862);
FORCEPROP 1 LASTPIN (-1475 2850) $PN 2
J 0
(-1513 2862);
DISPLAY 0.489362 (-1513 2862);
PAINT MONO (-1513 2862);
FORCEPROP 1 LAST VALUE 4.7K
J 0
(-1450 2850);
DISPLAY 0.489362 (-1450 2850);
PAINT SKYBLUE (-1450 2850);
FORCEPROP 1 LAST PACK_TYPE 0402LF
J 0
(-1325 2700);
DISPLAY 0.510638 (-1325 2700);
PAINT SKYBLUE (-1325 2700);
DISPLAY INVISIBLE (-1325 2700);
FORCEPROP 1 LAST PART_NUMBER TMP_QCS24702JB38
J 0
(-1625 2950);
DISPLAY 0.510638 (-1625 2950);
PAINT SKYBLUE (-1625 2950);
DISPLAY INVISIBLE (-1625 2950);
FORCEPROP 1 LAST TOLERANCE 5%
J 0
(-1450 2850);
DISPLAY 0.510638 (-1450 2850);
PAINT SKYBLUE (-1450 2850);
DISPLAY INVISIBLE (-1450 2850);
FORCEPROP 1 LAST MATERIAL CHIP
J 0
(-1475 2825);
DISPLAY 0.489362 (-1475 2825);
PAINT SKYBLUE (-1475 2825);
DISPLAY INVISIBLE (-1475 2825);
FORCEPROP 1 LAST WATTAGE 1/16W
J 2
(-1600 2700);
DISPLAY 0.510638 (-1600 2700);
PAINT SKYBLUE (-1600 2700);
DISPLAY INVISIBLE (-1600 2700);
FORCEPROP 1 LAST PATH I153
J 0
(-1625 3000);
DISPLAY 0.978723 (-1625 3000);
PAINT WHITE (-1625 3000);
DISPLAY INVISIBLE (-1625 3000);
FORCEPROP 2 LAST CDS_LIB pure_quanta
J 0
(-1575 2850);
DISPLAY INVISIBLE (-1575 2850);
FORCEADD Q_RES..1
(-1575 2900);
FORCEPROP 1 LAST LOCATION R26
J 0
(-1750 2900);
DISPLAY 0.489362 (-1750 2900);
PAINT SKYBLUE (-1750 2900);
FORCEPROP 0 LAST $SEC 1
J 0
(-1675 2975);
DISPLAY 0.680851 (-1675 2975);
PAINT MONO (-1675 2975);
DISPLAY INVISIBLE (-1675 2975);
FORCEPROP 0 LAST CDS_SEC 1
J 0
(-1675 2975);
DISPLAY 1.021277 (-1675 2975);
DISPLAY INVISIBLE (-1675 2975);
FORCEPROP 1 LASTPIN (-1675 2900) $PN 1
J 0
(-1663 2912);
DISPLAY 0.489362 (-1663 2912);
PAINT MONO (-1663 2912);
FORCEPROP 1 LASTPIN (-1475 2900) $PN 2
J 0
(-1513 2912);
DISPLAY 0.489362 (-1513 2912);
PAINT MONO (-1513 2912);
FORCEPROP 1 LAST VALUE 4.7K
J 0
(-1450 2900);
DISPLAY 0.489362 (-1450 2900);
PAINT SKYBLUE (-1450 2900);
FORCEPROP 1 LAST PACK_TYPE 0402LF
J 0
(-1325 2750);
DISPLAY 0.510638 (-1325 2750);
PAINT SKYBLUE (-1325 2750);
DISPLAY INVISIBLE (-1325 2750);
FORCEPROP 1 LAST PART_NUMBER TMP_QCS24702JB38
J 0
(-1625 3000);
DISPLAY 0.510638 (-1625 3000);
PAINT SKYBLUE (-1625 3000);
DISPLAY INVISIBLE (-1625 3000);
FORCEPROP 1 LAST TOLERANCE 5%
J 0
(-1450 2900);
DISPLAY 0.510638 (-1450 2900);
PAINT SKYBLUE (-1450 2900);
DISPLAY INVISIBLE (-1450 2900);
FORCEPROP 1 LAST MATERIAL CHIP
J 0
(-1475 2875);
DISPLAY 0.489362 (-1475 2875);
PAINT SKYBLUE (-1475 2875);
DISPLAY INVISIBLE (-1475 2875);
FORCEPROP 1 LAST WATTAGE 1/16W
J 2
(-1600 2750);
DISPLAY 0.510638 (-1600 2750);
PAINT SKYBLUE (-1600 2750);
DISPLAY INVISIBLE (-1600 2750);
FORCEPROP 1 LAST PATH I154
J 0
(-1625 3050);
DISPLAY 0.978723 (-1625 3050);
PAINT WHITE (-1625 3050);
DISPLAY INVISIBLE (-1625 3050);
FORCEPROP 2 LAST CDS_LIB pure_quanta
J 0
(-1575 2900);
DISPLAY INVISIBLE (-1575 2900);
FORCEADD Q_RES..1
(-1575 2750);
FORCEPROP 1 LAST LOCATION R45
J 0
(-1750 2750);
DISPLAY 0.489362 (-1750 2750);
PAINT SKYBLUE (-1750 2750);
FORCEPROP 0 LAST $SEC 1
J 0
(-1675 2825);
DISPLAY 0.680851 (-1675 2825);
PAINT MONO (-1675 2825);
DISPLAY INVISIBLE (-1675 2825);
FORCEPROP 0 LAST CDS_SEC 1
J 0
(-1675 2825);
DISPLAY 1.021277 (-1675 2825);
DISPLAY INVISIBLE (-1675 2825);
FORCEPROP 1 LASTPIN (-1675 2750) $PN 1
J 0
(-1663 2762);
DISPLAY 0.489362 (-1663 2762);
PAINT MONO (-1663 2762);
FORCEPROP 1 LASTPIN (-1475 2750) $PN 2
J 0
(-1513 2762);
DISPLAY 0.489362 (-1513 2762);
PAINT MONO (-1513 2762);
FORCEPROP 1 LAST VALUE 4.7K
J 0
(-1450 2750);
DISPLAY 0.489362 (-1450 2750);
PAINT SKYBLUE (-1450 2750);
FORCEPROP 1 LAST PACK_TYPE 0402LF
J 0
(-1325 2600);
DISPLAY 0.510638 (-1325 2600);
PAINT SKYBLUE (-1325 2600);
DISPLAY INVISIBLE (-1325 2600);
FORCEPROP 1 LAST PART_NUMBER TMP_QCS24702JB38
J 0
(-1625 2850);
DISPLAY 0.510638 (-1625 2850);
PAINT SKYBLUE (-1625 2850);
DISPLAY INVISIBLE (-1625 2850);
FORCEPROP 1 LAST TOLERANCE 5%
J 0
(-1450 2750);
DISPLAY 0.510638 (-1450 2750);
PAINT SKYBLUE (-1450 2750);
DISPLAY INVISIBLE (-1450 2750);
FORCEPROP 1 LAST MATERIAL CHIP
J 0
(-1475 2725);
DISPLAY 0.489362 (-1475 2725);
PAINT SKYBLUE (-1475 2725);
DISPLAY INVISIBLE (-1475 2725);
FORCEPROP 1 LAST WATTAGE 1/16W
J 2
(-1600 2600);
DISPLAY 0.510638 (-1600 2600);
PAINT SKYBLUE (-1600 2600);
DISPLAY INVISIBLE (-1600 2600);
FORCEPROP 1 LAST PATH I155
J 0
(-1625 2900);
DISPLAY 0.978723 (-1625 2900);
PAINT WHITE (-1625 2900);
DISPLAY INVISIBLE (-1625 2900);
FORCEPROP 2 LAST CDS_LIB pure_quanta
J 0
(-1575 2750);
DISPLAY INVISIBLE (-1575 2750);
FORCEADD OFFPAGE..1
(-5650 4775);
FORCEPROP 2 LAST $XR1 111 
J 0
(-6021 4775);
DISPLAY 0.638298 (-6021 4775);
PAINT MONO (-6021 4775);
FORCEPROP 2 LAST $XR0 83 
J 0
(-5901 4775);
DISPLAY 0.638298 (-5901 4775);
PAINT MONO (-5901 4775);
FORCEPROP 2 LAST PATH I161
J 0
(-5600 4850);
DISPLAY 0.680851 (-5600 4850);
DISPLAY INVISIBLE (-5600 4850);
FORCEPROP 1 LAST COMMENT_BODY TRUE
J 0
(-5525 4675);
DISPLAY 0.872340 (-5525 4675);
PAINT GREEN (-5525 4675);
DISPLAY INVISIBLE (-5525 4675);
FORCEPROP 1 LAST OFFPAGE TRUE
J 0
(-5325 4650);
DISPLAY 0.872340 (-5325 4650);
PAINT GREEN (-5325 4650);
DISPLAY INVISIBLE (-5325 4650);
FORCEPROP 2 LAST CDS_LIB standard
J 0
(-5650 4775);
DISPLAY INVISIBLE (-5650 4775);
FORCEADD Q_RES..1
(-4850 4775);
FORCEPROP 1 LAST LOCATION R1229
J 0
(-5050 4775);
DISPLAY 0.489362 (-5050 4775);
PAINT SKYBLUE (-5050 4775);
FORCEPROP 0 LAST $SEC 1
J 0
(-4975 4825);
DISPLAY 0.680851 (-4975 4825);
PAINT MONO (-4975 4825);
DISPLAY INVISIBLE (-4975 4825);
FORCEPROP 0 LAST CDS_SEC 1
J 0
(-4975 4825);
DISPLAY 1.021277 (-4975 4825);
DISPLAY INVISIBLE (-4975 4825);
FORCEPROP 1 LASTPIN (-4950 4775) $PN 1
J 0
(-4938 4787);
DISPLAY 0.489362 (-4938 4787);
PAINT MONO (-4938 4787);
FORCEPROP 1 LASTPIN (-4750 4775) $PN 2
J 0
(-4788 4787);
DISPLAY 0.489362 (-4788 4787);
PAINT MONO (-4788 4787);
FORCEPROP 1 LAST VALUE 0
J 2
(-4725 4775);
DISPLAY 0.489362 (-4725 4775);
PAINT SKYBLUE (-4725 4775);
FORCEPROP 1 LAST WATTAGE 1/16W
J 2
(-4450 4700);
DISPLAY 0.489362 (-4450 4700);
PAINT SKYBLUE (-4450 4700);
DISPLAY INVISIBLE (-4450 4700);
FORCEPROP 1 LAST MATERIAL CHIP
J 0
(-4425 4700);
DISPLAY 0.489362 (-4425 4700);
PAINT SKYBLUE (-4425 4700);
DISPLAY INVISIBLE (-4425 4700);
FORCEPROP 1 LAST TOLERANCE 5%
J 0
(-4875 4700);
DISPLAY 0.489362 (-4875 4700);
PAINT SKYBLUE (-4875 4700);
DISPLAY INVISIBLE (-4875 4700);
FORCEPROP 1 LAST PART_NUMBER CS00002JB38
J 0
(-4825 4825);
DISPLAY 0.489362 (-4825 4825);
PAINT SKYBLUE (-4825 4825);
DISPLAY INVISIBLE (-4825 4825);
FORCEPROP 1 LAST PACK_TYPE 0402LF
J 0
(-4800 4700);
DISPLAY 0.489362 (-4800 4700);
PAINT SKYBLUE (-4800 4700);
DISPLAY INVISIBLE (-4800 4700);
FORCEPROP 1 LAST PATH I162
J 0
(-4900 4925);
DISPLAY 0.978723 (-4900 4925);
PAINT WHITE (-4900 4925);
DISPLAY INVISIBLE (-4900 4925);
FORCEPROP 2 LAST CDS_LIB pure_quanta
J 0
(-4850 4775);
DISPLAY INVISIBLE (-4850 4775);
FORCEADD UNIVERSAL_GND..1
(-1225 4200);
FORCEPROP 3 LASTPIN (-1225 4250) SIG_NAME GND\g
J 0
(-1215 4260);
DISPLAY 0.659574 (-1215 4260);
PAINT MONO (-1215 4260);
DISPLAY INVISIBLE (-1215 4260);
FORCEPROP 1 LAST HDL_POWER GND
J 1
(-1200 4125);
DISPLAY 0.489362 (-1200 4125);
PAINT GREEN (-1200 4125);
FORCEPROP 1 LAST PATH I166
J 0
(-1150 4200);
DISPLAY 0.872340 (-1150 4200);
PAINT AQUA (-1150 4200);
DISPLAY INVISIBLE (-1150 4200);
FORCEPROP 2 LAST CDS_LIB pure_quanta_power
J 0
(-1225 4200);
DISPLAY INVISIBLE (-1225 4200);
FORCEADD Q_RES..1
(-1700 4675);
FORCEPROP 1 LAST LOCATION R1230
J 0
(-1900 4675);
DISPLAY 0.489362 (-1900 4675);
PAINT SKYBLUE (-1900 4675);
FORCEPROP 0 LAST $SEC 1
J 0
(-1575 4700);
DISPLAY 0.680851 (-1575 4700);
PAINT MONO (-1575 4700);
DISPLAY INVISIBLE (-1575 4700);
FORCEPROP 0 LAST CDS_SEC 1
J 0
(-1575 4700);
DISPLAY 1.021277 (-1575 4700);
DISPLAY INVISIBLE (-1575 4700);
FORCEPROP 1 LASTPIN (-1800 4675) $PN 1
J 0
(-1788 4687);
DISPLAY 0.489362 (-1788 4687);
PAINT MONO (-1788 4687);
FORCEPROP 1 LASTPIN (-1600 4675) $PN 2
J 0
(-1638 4687);
DISPLAY 0.489362 (-1638 4687);
PAINT MONO (-1638 4687);
FORCEPROP 1 LAST VALUE 0
J 2
(-1575 4675);
DISPLAY 0.489362 (-1575 4675);
PAINT SKYBLUE (-1575 4675);
FORCEPROP 1 LAST PACK_TYPE 0402LF
J 0
(-1650 4600);
DISPLAY 0.489362 (-1650 4600);
PAINT SKYBLUE (-1650 4600);
DISPLAY INVISIBLE (-1650 4600);
FORCEPROP 1 LAST PART_NUMBER CS00002JB38
J 0
(-1675 4725);
DISPLAY 0.489362 (-1675 4725);
PAINT SKYBLUE (-1675 4725);
DISPLAY INVISIBLE (-1675 4725);
FORCEPROP 1 LAST TOLERANCE 5%
J 0
(-1725 4600);
DISPLAY 0.489362 (-1725 4600);
PAINT SKYBLUE (-1725 4600);
DISPLAY INVISIBLE (-1725 4600);
FORCEPROP 1 LAST MATERIAL CHIP
J 0
(-1275 4600);
DISPLAY 0.489362 (-1275 4600);
PAINT SKYBLUE (-1275 4600);
DISPLAY INVISIBLE (-1275 4600);
FORCEPROP 1 LAST WATTAGE 1/16W
J 2
(-1300 4600);
DISPLAY 0.489362 (-1300 4600);
PAINT SKYBLUE (-1300 4600);
DISPLAY INVISIBLE (-1300 4600);
FORCEPROP 1 LAST PATH I167
J 0
(-1750 4825);
DISPLAY 0.978723 (-1750 4825);
PAINT WHITE (-1750 4825);
DISPLAY INVISIBLE (-1750 4825);
FORCEPROP 2 LAST CDS_LIB pure_quanta
J 0
(-1700 4675);
DISPLAY INVISIBLE (-1700 4675);
FORCEADD OFFPAGE..4
(-800 4725);
FORCEPROP 2 LAST $XR0 79 
J 0
(-614 4725);
DISPLAY 0.638298 (-614 4725);
PAINT MONO (-614 4725);
FORCEPROP 2 LAST PATH I170
J 0
(-625 4800);
DISPLAY 0.680851 (-625 4800);
DISPLAY INVISIBLE (-625 4800);
FORCEPROP 1 LAST COMMENT_BODY TRUE
J 0
(-825 4625);
DISPLAY 0.872340 (-825 4625);
PAINT GREEN (-825 4625);
DISPLAY INVISIBLE (-825 4625);
FORCEPROP 1 LAST OFFPAGE TRUE
J 0
(-475 4600);
DISPLAY 0.872340 (-475 4600);
PAINT GREEN (-475 4600);
DISPLAY INVISIBLE (-475 4600);
FORCEPROP 2 LAST CDS_LIB standard
J 0
(-800 4725);
DISPLAY INVISIBLE (-800 4725);
FORCEADD OFFPAGE..4
(-800 4675);
FORCEPROP 2 LAST $XR0 79 
J 0
(-614 4675);
DISPLAY 0.638298 (-614 4675);
PAINT MONO (-614 4675);
FORCEPROP 2 LAST PATH I171
J 0
(-625 4750);
DISPLAY 0.680851 (-625 4750);
DISPLAY INVISIBLE (-625 4750);
FORCEPROP 1 LAST COMMENT_BODY TRUE
J 0
(-825 4575);
DISPLAY 0.872340 (-825 4575);
PAINT GREEN (-825 4575);
DISPLAY INVISIBLE (-825 4575);
FORCEPROP 1 LAST OFFPAGE TRUE
J 0
(-475 4550);
DISPLAY 0.872340 (-475 4550);
PAINT GREEN (-475 4550);
DISPLAY INVISIBLE (-475 4550);
FORCEPROP 2 LAST CDS_LIB standard
J 0
(-800 4675);
DISPLAY INVISIBLE (-800 4675);
FORCEADD Q_RES..2
(-6850 3575);
FORCEPROP 1 LAST LOCATION R1228
J 0
(-6805 3700);
DISPLAY 0.489362 (-6805 3700);
PAINT SKYBLUE (-6805 3700);
FORCEPROP 2 LAST $SEC 1
J 0
(-6800 3800);
DISPLAY 0.680851 (-6800 3800);
PAINT MONO (-6800 3800);
DISPLAY INVISIBLE (-6800 3800);
FORCEPROP 2 LAST CDS_SEC 1
J 0
(-6800 3800);
DISPLAY 0.680851 (-6800 3800);
DISPLAY INVISIBLE (-6800 3800);
FORCEPROP 1 LASTPIN (-6850 3675) $PN 1
J 0
(-6845 3637);
DISPLAY 0.489362 (-6845 3637);
PAINT MONO (-6845 3637);
FORCEPROP 1 LASTPIN (-6850 3475) $PN 2
J 0
(-6845 3485);
DISPLAY 0.489362 (-6845 3485);
PAINT MONO (-6845 3485);
FORCEPROP 1 LAST PACK_TYPE 0402LF
J 0
(-6800 3450);
DISPLAY 0.489362 (-6800 3450);
PAINT SKYBLUE (-6800 3450);
FORCEPROP 1 LAST VALUE 4.7K
J 0
(-6805 3650);
DISPLAY 0.489362 (-6805 3650);
PAINT SKYBLUE (-6805 3650);
FORCEPROP 1 LAST TOLERANCE 1%
J 0
(-6805 3600);
DISPLAY 0.489362 (-6805 3600);
PAINT SKYBLUE (-6805 3600);
FORCEPROP 1 LAST MATERIAL EMPTY
J 0
(-6810 3500);
DISPLAY 0.489362 (-6810 3500);
PAINT RED (-6810 3500);
FORCEPROP 1 LAST WATTAGE 1/16W
J 0
(-6810 3550);
DISPLAY 0.489362 (-6810 3550);
PAINT SKYBLUE (-6810 3550);
FORCEPROP 1 LAST PART_NUMBER CS24702FB10
J 0
(-6810 3450);
DISPLAY 0.617021 (-6810 3450);
PAINT SKYBLUE (-6810 3450);
DISPLAY INVISIBLE (-6810 3450);
FORCEPROP 1 LAST PATH I174
J 0
(-6800 3750);
DISPLAY 0.978723 (-6800 3750);
PAINT WHITE (-6800 3750);
DISPLAY INVISIBLE (-6800 3750);
FORCEPROP 2 LAST CDS_LIB pure_quanta
J 0
(-6850 3575);
DISPLAY INVISIBLE (-6850 3575);
FORCEADD UNIVERSAL_POWER..1
(-6850 3800);
FORCEPROP 3 LASTPIN (-6850 3750) SIG_NAME P3V3\g
J 0
(-6840 3760);
DISPLAY 0.659574 (-6840 3760);
PAINT MONO (-6840 3760);
DISPLAY INVISIBLE (-6840 3760);
FORCEPROP 1 LAST HDL_POWER P3V3
J 1
(-6850 3850);
DISPLAY 0.489362 (-6850 3850);
PAINT GREEN (-6850 3850);
FORCEPROP 1 LAST PATH I175
J 0
(-6800 3825);
DISPLAY 0.872340 (-6800 3825);
PAINT AQUA (-6800 3825);
DISPLAY INVISIBLE (-6800 3825);
FORCEPROP 2 LAST CDS_LIB pure_quanta_power
J 0
(-6850 3800);
DISPLAY INVISIBLE (-6850 3800);
FORCEADD UNIVERSAL_GND..1
(-6850 2950);
FORCEPROP 3 LASTPIN (-6850 3000) SIG_NAME GND\g
J 0
(-6840 3010);
DISPLAY 0.659574 (-6840 3010);
PAINT MONO (-6840 3010);
DISPLAY INVISIBLE (-6840 3010);
FORCEPROP 1 LAST HDL_POWER GND
J 1
(-6825 2875);
DISPLAY 0.872340 (-6825 2875);
PAINT GREEN (-6825 2875);
DISPLAY INVISIBLE (-6825 2875);
FORCEPROP 1 LAST PATH I176
J 0
(-6775 2950);
DISPLAY 0.872340 (-6775 2950);
PAINT AQUA (-6775 2950);
DISPLAY INVISIBLE (-6775 2950);
FORCEPROP 2 LAST CDS_LIB pure_quanta_power
J 0
(-6850 2950);
DISPLAY INVISIBLE (-6850 2950);
FORCEADD OFFPAGE..2
(-5900 3325);
FORCEPROP 2 LAST $XR1 111 
J 0
(-5621 3325);
DISPLAY 0.638298 (-5621 3325);
PAINT MONO (-5621 3325);
FORCEPROP 2 LAST $XR0 83 
J 0
(-5711 3325);
DISPLAY 0.638298 (-5711 3325);
PAINT MONO (-5711 3325);
FORCEPROP 2 LAST PATH I177
J 0
(-5725 3400);
DISPLAY 0.680851 (-5725 3400);
DISPLAY INVISIBLE (-5725 3400);
FORCEPROP 1 LAST COMMENT_BODY TRUE
J 0
(-5945 3230);
DISPLAY 0.872340 (-5945 3230);
PAINT GREEN (-5945 3230);
DISPLAY INVISIBLE (-5945 3230);
FORCEPROP 1 LAST OFFPAGE TRUE
J 0
(-5575 3200);
DISPLAY 0.723404 (-5575 3200);
PAINT GREEN (-5575 3200);
DISPLAY INVISIBLE (-5575 3200);
FORCEPROP 2 LAST CDS_LIB standard
J 0
(-5900 3325);
DISPLAY INVISIBLE (-5900 3325);
FORCEADD Q_RES..1
(-1675 4475);
FORCEPROP 1 LAST LOCATION R1232
J 0
(-1900 4475);
DISPLAY 0.489362 (-1900 4475);
PAINT SKYBLUE (-1900 4475);
FORCEPROP 2 LAST $SEC 1
J 0
(-1725 4675);
DISPLAY 0.680851 (-1725 4675);
PAINT MONO (-1725 4675);
DISPLAY INVISIBLE (-1725 4675);
FORCEPROP 2 LAST CDS_SEC 1
J 0
(-1725 4675);
DISPLAY 0.680851 (-1725 4675);
DISPLAY INVISIBLE (-1725 4675);
FORCEPROP 1 LASTPIN (-1775 4475) $PN 1
J 0
(-1763 4487);
DISPLAY 0.489362 (-1763 4487);
PAINT MONO (-1763 4487);
FORCEPROP 1 LASTPIN (-1575 4475) $PN 2
J 0
(-1613 4487);
DISPLAY 0.489362 (-1613 4487);
PAINT MONO (-1613 4487);
FORCEPROP 1 LAST VALUE 100
J 2
(-1550 4475);
DISPLAY 0.489362 (-1550 4475);
PAINT SKYBLUE (-1550 4475);
FORCEPROP 1 LAST MATERIAL EMPTY
J 0
(-1525 4475);
DISPLAY 0.489362 (-1525 4475);
PAINT RED (-1525 4475);
FORCEPROP 1 LAST PACK_TYPE 0402LF
J 0
(-1425 4325);
DISPLAY 0.978723 (-1425 4325);
PAINT SKYBLUE (-1425 4325);
DISPLAY INVISIBLE (-1425 4325);
FORCEPROP 1 LAST PART_NUMBER TMP_QCS11002FB22
J 0
(-1725 4575);
DISPLAY 0.978723 (-1725 4575);
PAINT SKYBLUE (-1725 4575);
DISPLAY INVISIBLE (-1725 4575);
FORCEPROP 1 LAST TOLERANCE 1%
J 0
(-1675 4375);
DISPLAY 0.978723 (-1675 4375);
PAINT SKYBLUE (-1675 4375);
DISPLAY INVISIBLE (-1675 4375);
FORCEPROP 1 LAST WATTAGE 1/16W
J 2
(-1700 4325);
DISPLAY 0.978723 (-1700 4325);
PAINT SKYBLUE (-1700 4325);
DISPLAY INVISIBLE (-1700 4325);
FORCEPROP 1 LAST PATH I178
J 0
(-1725 4625);
DISPLAY 0.978723 (-1725 4625);
PAINT WHITE (-1725 4625);
DISPLAY INVISIBLE (-1725 4625);
FORCEPROP 2 LAST CDS_LIB pure_quanta
J 0
(-1675 4475);
DISPLAY INVISIBLE (-1675 4475);
FORCEADD Q_RES..1
(-1675 4375);
FORCEPROP 1 LAST LOCATION R1233
J 0
(-1900 4375);
DISPLAY 0.489362 (-1900 4375);
PAINT SKYBLUE (-1900 4375);
FORCEPROP 2 LAST $SEC 1
J 0
(-1725 4575);
DISPLAY 0.680851 (-1725 4575);
PAINT MONO (-1725 4575);
DISPLAY INVISIBLE (-1725 4575);
FORCEPROP 2 LAST CDS_SEC 1
J 0
(-1725 4575);
DISPLAY 0.680851 (-1725 4575);
DISPLAY INVISIBLE (-1725 4575);
FORCEPROP 1 LASTPIN (-1775 4375) $PN 1
J 0
(-1763 4387);
DISPLAY 0.489362 (-1763 4387);
PAINT MONO (-1763 4387);
FORCEPROP 1 LASTPIN (-1575 4375) $PN 2
J 0
(-1613 4387);
DISPLAY 0.489362 (-1613 4387);
PAINT MONO (-1613 4387);
FORCEPROP 1 LAST VALUE 100
J 2
(-1550 4375);
DISPLAY 0.489362 (-1550 4375);
PAINT SKYBLUE (-1550 4375);
FORCEPROP 1 LAST MATERIAL EMPTY
J 0
(-1525 4375);
DISPLAY 0.489362 (-1525 4375);
PAINT RED (-1525 4375);
FORCEPROP 1 LAST PACK_TYPE 0402LF
J 0
(-1425 4225);
DISPLAY 0.978723 (-1425 4225);
PAINT SKYBLUE (-1425 4225);
DISPLAY INVISIBLE (-1425 4225);
FORCEPROP 1 LAST PART_NUMBER TMP_QCS11002FB22
J 0
(-1725 4475);
DISPLAY 0.978723 (-1725 4475);
PAINT SKYBLUE (-1725 4475);
DISPLAY INVISIBLE (-1725 4475);
FORCEPROP 1 LAST TOLERANCE 1%
J 0
(-1675 4275);
DISPLAY 0.978723 (-1675 4275);
PAINT SKYBLUE (-1675 4275);
DISPLAY INVISIBLE (-1675 4275);
FORCEPROP 1 LAST WATTAGE 1/16W
J 2
(-1700 4225);
DISPLAY 0.978723 (-1700 4225);
PAINT SKYBLUE (-1700 4225);
DISPLAY INVISIBLE (-1700 4225);
FORCEPROP 1 LAST PATH I179
J 0
(-1725 4525);
DISPLAY 0.978723 (-1725 4525);
PAINT WHITE (-1725 4525);
DISPLAY INVISIBLE (-1725 4525);
FORCEPROP 2 LAST CDS_LIB pure_quanta
J 0
(-1675 4375);
DISPLAY INVISIBLE (-1675 4375);
FORCEADD Q_RES..1
(-1700 4725);
FORCEPROP 1 LAST LOCATION R1260
J 0
(-1900 4725);
DISPLAY 0.489362 (-1900 4725);
PAINT SKYBLUE (-1900 4725);
FORCEPROP 0 LAST $SEC 1
J 0
(-1900 4775);
DISPLAY 0.680851 (-1900 4775);
PAINT MONO (-1900 4775);
DISPLAY INVISIBLE (-1900 4775);
FORCEPROP 0 LAST CDS_SEC 1
J 0
(-1900 4775);
DISPLAY 0.680851 (-1900 4775);
DISPLAY INVISIBLE (-1900 4775);
FORCEPROP 1 LASTPIN (-1800 4725) $PN 1
J 0
(-1788 4737);
DISPLAY 0.489362 (-1788 4737);
PAINT MONO (-1788 4737);
FORCEPROP 1 LASTPIN (-1600 4725) $PN 2
J 0
(-1638 4737);
DISPLAY 0.489362 (-1638 4737);
PAINT MONO (-1638 4737);
FORCEPROP 1 LAST VALUE 0
J 2
(-1575 4725);
DISPLAY 0.489362 (-1575 4725);
PAINT SKYBLUE (-1575 4725);
FORCEPROP 1 LAST PACK_TYPE 0402LF
J 0
(-1650 4650);
DISPLAY 0.489362 (-1650 4650);
PAINT SKYBLUE (-1650 4650);
DISPLAY INVISIBLE (-1650 4650);
FORCEPROP 1 LAST PART_NUMBER CS00002JB38
J 0
(-1675 4775);
DISPLAY 0.489362 (-1675 4775);
PAINT SKYBLUE (-1675 4775);
DISPLAY INVISIBLE (-1675 4775);
FORCEPROP 1 LAST TOLERANCE 5%
J 0
(-1725 4650);
DISPLAY 0.489362 (-1725 4650);
PAINT SKYBLUE (-1725 4650);
DISPLAY INVISIBLE (-1725 4650);
FORCEPROP 1 LAST MATERIAL CHIP
J 0
(-1275 4650);
DISPLAY 0.489362 (-1275 4650);
PAINT SKYBLUE (-1275 4650);
DISPLAY INVISIBLE (-1275 4650);
FORCEPROP 1 LAST WATTAGE 1/16W
J 2
(-1300 4650);
DISPLAY 0.489362 (-1300 4650);
PAINT SKYBLUE (-1300 4650);
DISPLAY INVISIBLE (-1300 4650);
FORCEPROP 1 LAST PATH I181
J 0
(-1750 4875);
DISPLAY 0.978723 (-1750 4875);
PAINT WHITE (-1750 4875);
DISPLAY INVISIBLE (-1750 4875);
FORCEPROP 2 LAST CDS_LIB pure_quanta
J 0
(-1700 4725);
DISPLAY INVISIBLE (-1700 4725);
FORCEADD Q_RES..2
(-6850 3175);
FORCEPROP 1 LAST LOCATION R1259
J 0
(-6800 3275);
DISPLAY 0.489362 (-6800 3275);
PAINT SKYBLUE (-6800 3275);
FORCEPROP 0 LAST $SEC 1
J 0
(-6800 3325);
DISPLAY 0.680851 (-6800 3325);
PAINT MONO (-6800 3325);
DISPLAY INVISIBLE (-6800 3325);
FORCEPROP 0 LAST CDS_SEC 1
J 0
(-6800 3325);
DISPLAY 0.680851 (-6800 3325);
DISPLAY INVISIBLE (-6800 3325);
FORCEPROP 1 LASTPIN (-6850 3275) $PN 1
J 0
(-6845 3237);
DISPLAY 0.489362 (-6845 3237);
PAINT MONO (-6845 3237);
FORCEPROP 1 LASTPIN (-6850 3075) $PN 2
J 0
(-6845 3085);
DISPLAY 0.489362 (-6845 3085);
PAINT MONO (-6845 3085);
FORCEPROP 1 LAST PACK_TYPE 0402LF
J 0
(-6800 3050);
DISPLAY 0.489362 (-6800 3050);
PAINT SKYBLUE (-6800 3050);
FORCEPROP 1 LAST VALUE 4.7K
J 0
(-6805 3250);
DISPLAY 0.489362 (-6805 3250);
PAINT SKYBLUE (-6805 3250);
FORCEPROP 1 LAST TOLERANCE 1%
J 0
(-6805 3200);
DISPLAY 0.489362 (-6805 3200);
PAINT SKYBLUE (-6805 3200);
FORCEPROP 1 LAST MATERIAL EMPTY
J 0
(-6810 3100);
DISPLAY 0.489362 (-6810 3100);
PAINT RED (-6810 3100);
FORCEPROP 1 LAST WATTAGE 1/16W
J 0
(-6810 3150);
DISPLAY 0.489362 (-6810 3150);
PAINT SKYBLUE (-6810 3150);
FORCEPROP 1 LAST PART_NUMBER CS24702FB10
J 0
(-6810 3050);
DISPLAY 0.617021 (-6810 3050);
PAINT SKYBLUE (-6810 3050);
DISPLAY INVISIBLE (-6810 3050);
FORCEPROP 1 LAST PATH I182
J 0
(-6800 3350);
DISPLAY 0.978723 (-6800 3350);
PAINT WHITE (-6800 3350);
DISPLAY INVISIBLE (-6800 3350);
FORCEPROP 2 LAST CDS_LIB pure_quanta
J 0
(-6850 3175);
DISPLAY INVISIBLE (-6850 3175);
FORCEADD VCC_CORE..1
(-1775 3150);
FORCEPROP 3 LASTPIN (-1775 3100) SIG_NAME PVDD11_S3_P0\g
J 0
(-1765 3110);
DISPLAY 0.659574 (-1765 3110);
PAINT MONO (-1765 3110);
DISPLAY INVISIBLE (-1765 3110);
FORCEPROP 1 LAST HDL_POWER PVDD11_S3_P0
J 1
(-1775 3200);
DISPLAY 0.489362 (-1775 3200);
PAINT GREEN (-1775 3200);
FORCEPROP 1 LAST PATH I183
J 0
(-1725 3175);
DISPLAY 0.872340 (-1725 3175);
PAINT AQUA (-1725 3175);
DISPLAY INVISIBLE (-1725 3175);
FORCEPROP 2 LAST CDS_LIB pure_quanta_power
J 0
(-1775 3150);
DISPLAY INVISIBLE (-1775 3150);
FORCEADD VCC_CORE..1
(-2875 1800);
FORCEPROP 3 LASTPIN (-2875 1750) SIG_NAME PVDD11_S3_P0\g
J 0
(-2865 1760);
DISPLAY 0.659574 (-2865 1760);
PAINT MONO (-2865 1760);
DISPLAY INVISIBLE (-2865 1760);
FORCEPROP 1 LAST HDL_POWER PVDD11_S3_P0
J 1
(-2875 1850);
DISPLAY 0.489362 (-2875 1850);
PAINT GREEN (-2875 1850);
FORCEPROP 1 LAST PATH I184
J 0
(-2825 1825);
DISPLAY 0.872340 (-2825 1825);
PAINT AQUA (-2825 1825);
DISPLAY INVISIBLE (-2825 1825);
FORCEPROP 2 LAST CDS_LIB pure_quanta_power
J 0
(-2875 1800);
DISPLAY INVISIBLE (-2875 1800);
FORCEADD Q_RES..2
(-3100 2875);
FORCEPROP 1 LAST LOCATION R1417
J 0
(-3055 3000);
DISPLAY 0.489362 (-3055 3000);
PAINT SKYBLUE (-3055 3000);
FORCEPROP 0 LAST $SEC 1
J 0
(-3050 3025);
DISPLAY 0.680851 (-3050 3025);
PAINT MONO (-3050 3025);
DISPLAY INVISIBLE (-3050 3025);
FORCEPROP 0 LAST CDS_SEC 1
J 0
(-3050 3025);
DISPLAY 0.680851 (-3050 3025);
DISPLAY INVISIBLE (-3050 3025);
FORCEPROP 1 LASTPIN (-3100 2975) $PN 1
J 0
(-3095 2937);
DISPLAY 0.489362 (-3095 2937);
PAINT MONO (-3095 2937);
FORCEPROP 1 LASTPIN (-3100 2775) $PN 2
J 0
(-3095 2785);
DISPLAY 0.489362 (-3095 2785);
PAINT MONO (-3095 2785);
FORCEPROP 1 LAST VALUE 4.7K
J 0
(-3055 2950);
DISPLAY 0.489362 (-3055 2950);
PAINT SKYBLUE (-3055 2950);
FORCEPROP 1 LAST PACK_TYPE 0402LF
J 0
(-3050 2750);
DISPLAY 0.489362 (-3050 2750);
PAINT SKYBLUE (-3050 2750);
FORCEPROP 1 LAST MATERIAL CHIP
J 0
(-3060 2800);
DISPLAY 0.489362 (-3060 2800);
PAINT SKYBLUE (-3060 2800);
FORCEPROP 1 LAST WATTAGE 1/16W
J 0
(-3060 2850);
DISPLAY 0.489362 (-3060 2850);
PAINT SKYBLUE (-3060 2850);
FORCEPROP 1 LAST TOLERANCE 5%
J 0
(-3055 2900);
DISPLAY 0.489362 (-3055 2900);
PAINT SKYBLUE (-3055 2900);
FORCEPROP 1 LAST PART_NUMBER TMP_QCS24702JB38
J 0
(-3060 2750);
DISPLAY 0.489362 (-3060 2750);
PAINT SKYBLUE (-3060 2750);
DISPLAY INVISIBLE (-3060 2750);
FORCEPROP 1 LAST PATH I187
J 0
(-3050 3050);
DISPLAY 0.978723 (-3050 3050);
PAINT WHITE (-3050 3050);
DISPLAY INVISIBLE (-3050 3050);
FORCEPROP 2 LAST CDS_LIB pure_quanta
J 0
(-3100 2875);
DISPLAY INVISIBLE (-3100 2875);
FORCEADD UNIVERSAL_GND..1
R 2
(-3100 2000);
FORCEPROP 3 LASTPIN (-3100 2050) SIG_NAME GND\g
J 0
(-3090 2060);
DISPLAY 0.659574 (-3090 2060);
PAINT MONO (-3090 2060);
DISPLAY INVISIBLE (-3090 2060);
FORCEPROP 1 LAST HDL_POWER GND
J 1
(-3125 1925);
DISPLAY 0.702128 (-3125 1925);
PAINT GREEN (-3125 1925);
DISPLAY INVISIBLE (-3125 1925);
FORCEPROP 1 LAST PATH I188
J 2
(-3175 2000);
DISPLAY 0.872340 (-3175 2000);
PAINT AQUA (-3175 2000);
DISPLAY INVISIBLE (-3175 2000);
FORCEPROP 2 LAST CDS_LIB pure_quanta_power
J 0
(-3100 2000);
DISPLAY INVISIBLE (-3100 2000);
FORCEADD MOSFET_N_GSD..1
(-3125 2350);
FORCEPROP 1 LAST LOCATION Q15
J 0
(-3024 2395);
DISPLAY 0.489362 (-3024 2395);
PAINT SKYBLUE (-3024 2395);
FORCEPROP 0 LAST $SEC 1
J 0
(-3025 2575);
DISPLAY 0.680851 (-3025 2575);
PAINT MONO (-3025 2575);
DISPLAY INVISIBLE (-3025 2575);
FORCEPROP 0 LAST CDS_SEC 1
J 0
(-3025 2575);
DISPLAY 0.680851 (-3025 2575);
DISPLAY INVISIBLE (-3025 2575);
FORCEPROP 0 LASTPIN (-3100 2500) $PN D
R 1
J 0
(-3110 2510);
DISPLAY 0.489362 (-3110 2510);
PAINT MONO (-3110 2510);
FORCEPROP 0 LASTPIN (-3300 2300) $PN G
J 2
(-3310 2310);
DISPLAY 0.489362 (-3310 2310);
PAINT MONO (-3310 2310);
FORCEPROP 0 LASTPIN (-3100 2200) $PN S
R 1
J 2
(-3110 2190);
DISPLAY 0.489362 (-3110 2190);
PAINT MONO (-3110 2190);
FORCEPROP 2 LAST PART_TYPE SMLF
J 0
(-3025 2525);
DISPLAY 1.021277 (-3025 2525);
FORCEPROP 1 LAST MATERIAL IC
J 0
(-3024 2250);
DISPLAY 0.489362 (-3024 2250);
PAINT SKYBLUE (-3024 2250);
FORCEPROP 1 LAST PART_NUMBER BAM01380023
J 0
(-3024 2330);
DISPLAY 0.489362 (-3024 2330);
PAINT SKYBLUE (-3024 2330);
FORCEPROP 2 LAST VALUE NX138BK
J 0
(-3025 2475);
DISPLAY 0.489362 (-3025 2475);
PAINT SKYBLUE (-3025 2475);
FORCEPROP 1 LAST PATH I189
J 0
(-3125 2350);
DISPLAY 0.723404 (-3125 2350);
PAINT GREEN (-3125 2350);
DISPLAY INVISIBLE (-3125 2350);
FORCEPROP 2 LAST CDS_LIB pure_quanta
J 0
(-3125 2350);
DISPLAY INVISIBLE (-3125 2350);
FORCEPROP 1 LAST CDS_LMAN_SYM_OUTLINE -100,100,100,-100
J 0
(-3125 2350);
DISPLAY 0.468085 (-3125 2350);
PAINT GREEN (-3125 2350);
DISPLAY INVISIBLE (-3125 2350);
FORCEPROP 1 LAST NEEDS_NO_SIZE TRUE
J 0
(-3125 2350);
DISPLAY 0.468085 (-3125 2350);
PAINT GREEN (-3125 2350);
DISPLAY INVISIBLE (-3125 2350);
FORCEADD OFFPAGE..1
(-3950 2300);
FORCEPROP 2 LAST $XR1 80 
J 0
(-4292 2300);
DISPLAY 0.638298 (-4292 2300);
PAINT MONO (-4292 2300);
FORCEPROP 2 LAST $XR0 183 
J 0
(-4202 2300);
DISPLAY 0.638298 (-4202 2300);
PAINT MONO (-4202 2300);
FORCEPROP 2 LAST PATH I190
J 0
(-3900 2375);
DISPLAY 0.680851 (-3900 2375);
DISPLAY INVISIBLE (-3900 2375);
FORCEPROP 1 LAST COMMENT_BODY TRUE
J 0
(-3820 2200);
DISPLAY 1.106383 (-3820 2200);
PAINT PEACH (-3820 2200);
DISPLAY INVISIBLE (-3820 2200);
FORCEPROP 1 LAST OFFPAGE TRUE
J 0
(-3620 2170);
PAINT GREEN (-3620 2170);
DISPLAY INVISIBLE (-3620 2170);
FORCEPROP 2 LAST CDS_LIB standard
J 0
(-3950 2300);
DISPLAY INVISIBLE (-3950 2300);
FORCEADD VCC_CORE..1
(-3100 3075);
FORCEPROP 3 LASTPIN (-3100 3025) SIG_NAME PVDD11_S3_P0\g
J 0
(-3090 3035);
DISPLAY 0.659574 (-3090 3035);
PAINT MONO (-3090 3035);
DISPLAY INVISIBLE (-3090 3035);
FORCEPROP 1 LAST HDL_POWER PVDD11_S3_P0
J 1
(-3100 3125);
DISPLAY 0.489362 (-3100 3125);
PAINT GREEN (-3100 3125);
FORCEPROP 1 LAST PATH I191
J 0
(-3050 3100);
DISPLAY 0.872340 (-3050 3100);
PAINT AQUA (-3050 3100);
DISPLAY INVISIBLE (-3050 3100);
FORCEPROP 2 LAST CDS_LIB pure_quanta_power
J 0
(-3100 3075);
DISPLAY INVISIBLE (-3100 3075);
FORCEADD OFFPAGE..1
(-3400 975);
FORCEPROP 2 LAST $XR0 111 
J 0
(-3682 975);
DISPLAY 0.638298 (-3682 975);
PAINT MONO (-3682 975);
FORCEPROP 2 LAST PATH I192
J 0
(-3350 1050);
DISPLAY 0.680851 (-3350 1050);
DISPLAY INVISIBLE (-3350 1050);
FORCEPROP 1 LAST COMMENT_BODY TRUE
J 0
(-3275 875);
DISPLAY 0.872340 (-3275 875);
PAINT GREEN (-3275 875);
DISPLAY INVISIBLE (-3275 875);
FORCEPROP 1 LAST OFFPAGE TRUE
J 0
(-3075 850);
DISPLAY 0.872340 (-3075 850);
PAINT GREEN (-3075 850);
DISPLAY INVISIBLE (-3075 850);
FORCEPROP 2 LAST CDS_LIB standard
J 0
(-3400 975);
DISPLAY INVISIBLE (-3400 975);
FORCEADD Q_RES..1
(-2400 2675);
FORCEPROP 1 LAST LOCATION R5000
J 0
(-2575 2700);
DISPLAY 0.489362 (-2575 2700);
PAINT SKYBLUE (-2575 2700);
FORCEPROP 0 LAST $SEC 1
J 0
(-2425 2725);
DISPLAY 0.680851 (-2425 2725);
PAINT MONO (-2425 2725);
DISPLAY INVISIBLE (-2425 2725);
FORCEPROP 0 LAST CDS_SEC 1
J 0
(-2425 2725);
DISPLAY 0.680851 (-2425 2725);
DISPLAY INVISIBLE (-2425 2725);
FORCEPROP 1 LASTPIN (-2500 2675) $PN 1
J 0
(-2488 2687);
DISPLAY 0.787234 (-2488 2687);
PAINT MONO (-2488 2687);
FORCEPROP 1 LASTPIN (-2300 2675) $PN 2
J 0
(-2338 2687);
DISPLAY 0.787234 (-2338 2687);
PAINT MONO (-2338 2687);
FORCEPROP 1 LAST VALUE 0
J 2
(-2425 2700);
DISPLAY 0.489362 (-2425 2700);
PAINT SKYBLUE (-2425 2700);
FORCEPROP 2 LAST CDS_LIB pure_quanta
J 0
(-2400 2675);
DISPLAY INVISIBLE (-2400 2675);
FORCEPROP 1 LAST PATH I193
J 0
(-2450 2825);
DISPLAY 0.978723 (-2450 2825);
PAINT WHITE (-2450 2825);
DISPLAY INVISIBLE (-2450 2825);
FORCEPROP 1 LAST WATTAGE 1/16W
J 2
(-2000 2600);
DISPLAY 0.489362 (-2000 2600);
PAINT SKYBLUE (-2000 2600);
DISPLAY INVISIBLE (-2000 2600);
FORCEPROP 1 LAST MATERIAL CHIP
J 0
(-1975 2600);
DISPLAY 0.489362 (-1975 2600);
PAINT SKYBLUE (-1975 2600);
DISPLAY INVISIBLE (-1975 2600);
FORCEPROP 1 LAST TOLERANCE 5%
J 0
(-2425 2600);
DISPLAY 0.489362 (-2425 2600);
PAINT SKYBLUE (-2425 2600);
DISPLAY INVISIBLE (-2425 2600);
FORCEPROP 1 LAST PART_NUMBER CS00002JB38
J 0
(-2375 2725);
DISPLAY 0.489362 (-2375 2725);
PAINT SKYBLUE (-2375 2725);
DISPLAY INVISIBLE (-2375 2725);
FORCEPROP 1 LAST PACK_TYPE 0402LF
J 0
(-2350 2600);
DISPLAY 0.489362 (-2350 2600);
PAINT SKYBLUE (-2350 2600);
DISPLAY INVISIBLE (-2350 2600);
FORCEADD OFFPAGE..2
(-1900 2675);
FORCEPROP 2 LAST $XR0 111 
J 0
(-1711 2675);
DISPLAY 0.638298 (-1711 2675);
PAINT MONO (-1711 2675);
FORCEPROP 2 LAST CDS_LIB standard
J 0
(-1900 2675);
DISPLAY INVISIBLE (-1900 2675);
FORCEPROP 2 LAST PATH I194
J 0
(-1725 2750);
DISPLAY 0.680851 (-1725 2750);
DISPLAY INVISIBLE (-1725 2750);
FORCEPROP 1 LAST OFFPAGE TRUE
J 0
(-1575 2550);
DISPLAY 0.872340 (-1575 2550);
PAINT GREEN (-1575 2550);
DISPLAY INVISIBLE (-1575 2550);
FORCEPROP 1 LAST COMMENT_BODY TRUE
J 0
(-1945 2580);
DISPLAY 0.872340 (-1945 2580);
PAINT GREEN (-1945 2580);
DISPLAY INVISIBLE (-1945 2580);
FORCEADD VCC_CORE..1
(-4625 5575);
FORCEPROP 3 LASTPIN (-4625 5525) SIG_NAME P3V3_9ZX_VDDA_2\g
J 0
(-4615 5535);
DISPLAY 0.659574 (-4615 5535);
PAINT MONO (-4615 5535);
DISPLAY INVISIBLE (-4615 5535);
FORCEPROP 1 LAST HDL_POWER P3V3_9ZX_VDDA_2
J 1
(-4625 5625);
DISPLAY 0.489362 (-4625 5625);
PAINT GREEN (-4625 5625);
FORCEPROP 2 LAST ROOM DB2000_1_BCLK
J 0
(-4625 5675);
DISPLAY 0.808511 (-4625 5675);
PAINT RED (-4625 5675);
DISPLAY INVISIBLE (-4625 5675);
FORCEPROP 0 LAST VOLTAGE 3.3
J 0
(-4625 5725);
DISPLAY 1.021277 (-4625 5725);
PAINT SKYBLUE (-4625 5725);
DISPLAY INVISIBLE (-4625 5725);
FORCEPROP 1 LAST PATH I2
J 0
(-4575 5600);
DISPLAY 0.872340 (-4575 5600);
PAINT AQUA (-4575 5600);
DISPLAY INVISIBLE (-4575 5600);
FORCEPROP 2 LAST CDS_LIB pure_quanta_power
J 0
(-4625 5575);
DISPLAY INVISIBLE (-4625 5575);
FORCEPROP 2 LAST BOM_COST SYS_CLOCK
J 0
(-4625 5725);
DISPLAY 0.808511 (-4625 5725);
DISPLAY INVISIBLE (-4625 5725);
FORCEADD UNIVERSAL_POWER..1
(-4225 5950);
FORCEPROP 3 LASTPIN (-4225 5900) SIG_NAME P3V3_9ZX_VDD_2\g
J 0
(-4215 5910);
DISPLAY 0.659574 (-4215 5910);
PAINT MONO (-4215 5910);
DISPLAY INVISIBLE (-4215 5910);
FORCEPROP 1 LAST HDL_POWER P3V3_9ZX_VDD_2
J 1
(-4225 6000);
DISPLAY 0.489362 (-4225 6000);
PAINT GREEN (-4225 6000);
FORCEPROP 2 LAST ROOM DB2000_1_BCLK
J 0
(-4225 6050);
DISPLAY 0.808511 (-4225 6050);
PAINT RED (-4225 6050);
DISPLAY INVISIBLE (-4225 6050);
FORCEPROP 0 LAST VOLTAGE 3.3
J 0
(-4225 6100);
DISPLAY 1.021277 (-4225 6100);
PAINT SKYBLUE (-4225 6100);
DISPLAY INVISIBLE (-4225 6100);
FORCEPROP 1 LAST PATH I3
J 0
(-4175 5975);
DISPLAY 0.872340 (-4175 5975);
PAINT AQUA (-4175 5975);
DISPLAY INVISIBLE (-4175 5975);
FORCEPROP 2 LAST BOM_COST SYS_CLOCK
J 0
(-4225 6100);
DISPLAY 0.808511 (-4225 6100);
DISPLAY INVISIBLE (-4225 6100);
FORCEPROP 2 LAST CDS_LIB pure_quanta_power
J 0
(-4225 5950);
DISPLAY INVISIBLE (-4225 5950);
FORCEADD OFFPAGE..1
(-4850 5125);
FORCEPROP 2 LAST $XR0 55 
J 0
(-5101 5125);
DISPLAY 0.638298 (-5101 5125);
PAINT MONO (-5101 5125);
FORCEPROP 2 LAST PATH I38
J 0
(-4800 5200);
DISPLAY 1.021277 (-4800 5200);
DISPLAY INVISIBLE (-4800 5200);
FORCEPROP 1 LAST COMMENT_BODY TRUE
J 0
(-4725 5025);
DISPLAY 0.872340 (-4725 5025);
PAINT GREEN (-4725 5025);
DISPLAY INVISIBLE (-4725 5025);
FORCEPROP 1 LAST OFFPAGE TRUE
J 0
(-4525 5000);
DISPLAY 0.872340 (-4525 5000);
PAINT GREEN (-4525 5000);
DISPLAY INVISIBLE (-4525 5000);
FORCEPROP 2 LAST CDS_LIB standard
J 0
(-4850 5125);
DISPLAY INVISIBLE (-4850 5125);
FORCEADD OFFPAGE..1
(-4850 5175);
FORCEPROP 2 LAST $XR0 55 
J 0
(-5101 5175);
DISPLAY 0.638298 (-5101 5175);
PAINT MONO (-5101 5175);
FORCEPROP 2 LAST PATH I39
J 0
(-4800 5250);
DISPLAY 1.021277 (-4800 5250);
DISPLAY INVISIBLE (-4800 5250);
FORCEPROP 1 LAST COMMENT_BODY TRUE
J 0
(-4725 5075);
DISPLAY 0.872340 (-4725 5075);
PAINT GREEN (-4725 5075);
DISPLAY INVISIBLE (-4725 5075);
FORCEPROP 1 LAST OFFPAGE TRUE
J 0
(-4525 5050);
DISPLAY 0.872340 (-4525 5050);
PAINT GREEN (-4525 5050);
DISPLAY INVISIBLE (-4525 5050);
FORCEPROP 2 LAST CDS_LIB standard
J 0
(-4850 5175);
DISPLAY INVISIBLE (-4850 5175);
FORCEADD VCC_CORE..1
(-2625 5950);
FORCEPROP 3 LASTPIN (-2625 5900) SIG_NAME P3V3_9ZX_VDDA_2\g
J 0
(-2615 5910);
DISPLAY 0.659574 (-2615 5910);
PAINT MONO (-2615 5910);
DISPLAY INVISIBLE (-2615 5910);
FORCEPROP 1 LAST HDL_POWER P3V3_9ZX_VDDA_2
J 1
(-2625 6000);
DISPLAY 0.489362 (-2625 6000);
PAINT GREEN (-2625 6000);
FORCEPROP 2 LAST ROOM DB2000_1_BCLK
J 0
(-2625 6050);
DISPLAY 0.808511 (-2625 6050);
PAINT RED (-2625 6050);
DISPLAY INVISIBLE (-2625 6050);
FORCEPROP 0 LAST VOLTAGE 3.3
J 0
(-2625 6100);
DISPLAY 1.021277 (-2625 6100);
PAINT SKYBLUE (-2625 6100);
DISPLAY INVISIBLE (-2625 6100);
FORCEPROP 1 LAST PATH I4
J 0
(-2575 5975);
DISPLAY 0.872340 (-2575 5975);
PAINT AQUA (-2575 5975);
DISPLAY INVISIBLE (-2575 5975);
FORCEPROP 2 LAST BOM_COST SYS_CLOCK
J 0
(-2625 6100);
DISPLAY 0.808511 (-2625 6100);
DISPLAY INVISIBLE (-2625 6100);
FORCEPROP 2 LAST CDS_LIB pure_quanta_power
J 0
(-2625 5950);
DISPLAY INVISIBLE (-2625 5950);
FORCEADD VCC_CORE..1
(-6250 5675);
FORCEPROP 3 LASTPIN (-6250 5625) SIG_NAME P3V3_9ZX_VDDA_2\g
J 0
(-6240 5635);
DISPLAY 0.659574 (-6240 5635);
PAINT MONO (-6240 5635);
DISPLAY INVISIBLE (-6240 5635);
FORCEPROP 1 LAST HDL_POWER P3V3_9ZX_VDDA_2
J 1
(-6250 5725);
DISPLAY 0.489362 (-6250 5725);
PAINT GREEN (-6250 5725);
FORCEPROP 2 LAST ROOM DB2000_1_BCLK
J 0
(-6250 5775);
DISPLAY 0.808511 (-6250 5775);
PAINT RED (-6250 5775);
DISPLAY INVISIBLE (-6250 5775);
FORCEPROP 0 LAST VOLTAGE 3.3
J 0
(-6250 5825);
DISPLAY 1.021277 (-6250 5825);
PAINT SKYBLUE (-6250 5825);
DISPLAY INVISIBLE (-6250 5825);
FORCEPROP 1 LAST PATH I40
J 0
(-6200 5700);
DISPLAY 0.872340 (-6200 5700);
PAINT AQUA (-6200 5700);
DISPLAY INVISIBLE (-6200 5700);
FORCEPROP 2 LAST BOM_COST SYS_CLOCK
J 0
(-6250 5825);
DISPLAY 0.808511 (-6250 5825);
DISPLAY INVISIBLE (-6250 5825);
FORCEPROP 2 LAST CDS_LIB mstr_symbols
J 0
(-6250 5675);
DISPLAY INVISIBLE (-6250 5675);
FORCEADD Q_CAP..1
(-6250 5325);
FORCEPROP 1 LAST LOCATION C1234
J 0
(-6200 5425);
DISPLAY 0.489362 (-6200 5425);
PAINT SKYBLUE (-6200 5425);
FORCEPROP 0 LAST $SEC 1
J 0
(-6200 5475);
DISPLAY 0.680851 (-6200 5475);
PAINT MONO (-6200 5475);
DISPLAY INVISIBLE (-6200 5475);
FORCEPROP 0 LAST CDS_SEC 1
J 0
(-6200 5475);
DISPLAY 1.021277 (-6200 5475);
DISPLAY INVISIBLE (-6200 5475);
FORCEPROP 1 LASTPIN (-6250 5425) $PN 1
J 0
(-6240 5405);
DISPLAY 0.489362 (-6240 5405);
PAINT MONO (-6240 5405);
FORCEPROP 1 LASTPIN (-6250 5225) $PN 2
J 0
(-6240 5205);
DISPLAY 0.489362 (-6240 5205);
PAINT MONO (-6240 5205);
FORCEPROP 1 LAST PACK_TYPE 0402
J 0
(-6200 5175);
DISPLAY 0.489362 (-6200 5175);
PAINT SKYBLUE (-6200 5175);
FORCEPROP 1 LAST VOLTAGE 25V
J 0
(-6200 5325);
DISPLAY 0.489362 (-6200 5325);
PAINT SKYBLUE (-6200 5325);
FORCEPROP 1 LAST VALUE 0.1UF
J 0
(-6200 5375);
DISPLAY 0.489362 (-6200 5375);
PAINT SKYBLUE (-6200 5375);
FORCEPROP 1 LAST TOLERANCE 10%
J 0
(-6200 5275);
DISPLAY 0.489362 (-6200 5275);
PAINT SKYBLUE (-6200 5275);
FORCEPROP 1 LAST MATERIAL X7R
J 0
(-6200 5225);
DISPLAY 0.489362 (-6200 5225);
PAINT SKYBLUE (-6200 5225);
FORCEPROP 1 LAST PART_NUMBER CH4104K1B00
J 0
(-6200 5175);
DISPLAY 0.978723 (-6200 5175);
PAINT SKYBLUE (-6200 5175);
DISPLAY INVISIBLE (-6200 5175);
FORCEPROP 1 LAST PATH I41
J 0
(-6200 5475);
DISPLAY 0.978723 (-6200 5475);
PAINT WHITE (-6200 5475);
DISPLAY INVISIBLE (-6200 5475);
FORCEPROP 2 LAST CDS_LIB pure_quanta
J 0
(-6250 5325);
DISPLAY INVISIBLE (-6250 5325);
FORCEADD Q_CAP..1
(-6450 5325);
FORCEPROP 1 LAST LOCATION C1233
J 0
(-6400 5425);
DISPLAY 0.489362 (-6400 5425);
PAINT SKYBLUE (-6400 5425);
FORCEPROP 0 LAST $SEC 1
J 0
(-6400 5475);
DISPLAY 0.680851 (-6400 5475);
PAINT MONO (-6400 5475);
DISPLAY INVISIBLE (-6400 5475);
FORCEPROP 0 LAST CDS_SEC 1
J 0
(-6400 5475);
DISPLAY 1.021277 (-6400 5475);
DISPLAY INVISIBLE (-6400 5475);
FORCEPROP 1 LASTPIN (-6450 5425) $PN 1
J 0
(-6440 5405);
DISPLAY 0.489362 (-6440 5405);
PAINT MONO (-6440 5405);
FORCEPROP 1 LASTPIN (-6450 5225) $PN 2
J 0
(-6440 5205);
DISPLAY 0.489362 (-6440 5205);
PAINT MONO (-6440 5205);
FORCEPROP 1 LAST PACK_TYPE 0402
J 0
(-6400 5175);
DISPLAY 0.489362 (-6400 5175);
PAINT SKYBLUE (-6400 5175);
FORCEPROP 1 LAST VOLTAGE 25V
J 0
(-6400 5325);
DISPLAY 0.489362 (-6400 5325);
PAINT SKYBLUE (-6400 5325);
FORCEPROP 1 LAST VALUE 0.1UF
J 0
(-6400 5375);
DISPLAY 0.489362 (-6400 5375);
PAINT SKYBLUE (-6400 5375);
FORCEPROP 1 LAST TOLERANCE 10%
J 0
(-6400 5275);
DISPLAY 0.489362 (-6400 5275);
PAINT SKYBLUE (-6400 5275);
FORCEPROP 1 LAST MATERIAL X7R
J 0
(-6400 5225);
DISPLAY 0.489362 (-6400 5225);
PAINT SKYBLUE (-6400 5225);
FORCEPROP 1 LAST PART_NUMBER CH4104K1B00
J 0
(-6400 5175);
DISPLAY 0.978723 (-6400 5175);
PAINT SKYBLUE (-6400 5175);
DISPLAY INVISIBLE (-6400 5175);
FORCEPROP 1 LAST PATH I42
J 0
(-6400 5475);
DISPLAY 0.978723 (-6400 5475);
PAINT WHITE (-6400 5475);
DISPLAY INVISIBLE (-6400 5475);
FORCEPROP 2 LAST CDS_LIB pure_quanta
J 0
(-6450 5325);
DISPLAY INVISIBLE (-6450 5325);
FORCEADD Q_CAP..1
(-6700 5325);
FORCEPROP 1 LAST LOCATION C1232
J 0
(-6650 5425);
DISPLAY 0.489362 (-6650 5425);
PAINT SKYBLUE (-6650 5425);
FORCEPROP 0 LAST $SEC 1
J 0
(-6650 5475);
DISPLAY 0.680851 (-6650 5475);
PAINT MONO (-6650 5475);
DISPLAY INVISIBLE (-6650 5475);
FORCEPROP 0 LAST CDS_SEC 1
J 0
(-6650 5475);
DISPLAY 1.021277 (-6650 5475);
DISPLAY INVISIBLE (-6650 5475);
FORCEPROP 1 LASTPIN (-6700 5425) $PN 1
J 0
(-6690 5405);
DISPLAY 0.489362 (-6690 5405);
PAINT MONO (-6690 5405);
FORCEPROP 1 LASTPIN (-6700 5225) $PN 2
J 0
(-6690 5205);
DISPLAY 0.489362 (-6690 5205);
PAINT MONO (-6690 5205);
FORCEPROP 1 LAST PACK_TYPE C0402
J 0
(-6650 5175);
DISPLAY 0.489362 (-6650 5175);
PAINT SKYBLUE (-6650 5175);
FORCEPROP 1 LAST VOLTAGE 25V
J 0
(-6650 5325);
DISPLAY 0.489362 (-6650 5325);
PAINT SKYBLUE (-6650 5325);
FORCEPROP 1 LAST VALUE 1UF
J 0
(-6650 5375);
DISPLAY 0.489362 (-6650 5375);
PAINT SKYBLUE (-6650 5375);
FORCEPROP 1 LAST TOLERANCE 10%
J 0
(-6650 5275);
DISPLAY 0.489362 (-6650 5275);
PAINT SKYBLUE (-6650 5275);
FORCEPROP 1 LAST MATERIAL X6S
J 0
(-6650 5225);
DISPLAY 0.489362 (-6650 5225);
PAINT SKYBLUE (-6650 5225);
FORCEPROP 1 LAST PART_NUMBER CH5104KEB02
J 0
(-6650 5175);
DISPLAY 0.617021 (-6650 5175);
PAINT SKYBLUE (-6650 5175);
DISPLAY INVISIBLE (-6650 5175);
FORCEPROP 1 LAST PATH I43
J 0
(-6650 5475);
DISPLAY 0.978723 (-6650 5475);
PAINT WHITE (-6650 5475);
DISPLAY INVISIBLE (-6650 5475);
FORCEPROP 2 LAST CDS_LIB pure_quanta
J 0
(-6700 5325);
DISPLAY INVISIBLE (-6700 5325);
FORCEADD Q_RES..1
(-7200 5475);
FORCEPROP 1 LAST LOCATION R796
J 0
(-7250 5525);
DISPLAY 0.489362 (-7250 5525);
PAINT SKYBLUE (-7250 5525);
FORCEPROP 0 LAST $SEC 1
J 0
(-7250 5575);
DISPLAY 0.680851 (-7250 5575);
PAINT MONO (-7250 5575);
DISPLAY INVISIBLE (-7250 5575);
FORCEPROP 0 LAST CDS_SEC 1
J 0
(-7250 5575);
DISPLAY 1.021277 (-7250 5575);
DISPLAY INVISIBLE (-7250 5575);
FORCEPROP 1 LASTPIN (-7300 5475) $PN 1
J 0
(-7288 5487);
DISPLAY 0.489362 (-7288 5487);
PAINT MONO (-7288 5487);
FORCEPROP 1 LASTPIN (-7100 5475) $PN 2
J 0
(-7138 5487);
DISPLAY 0.489362 (-7138 5487);
PAINT MONO (-7138 5487);
FORCEPROP 1 LAST PACK_TYPE 0603LF
J 0
(-7050 5425);
DISPLAY 0.489362 (-7050 5425);
PAINT SKYBLUE (-7050 5425);
FORCEPROP 1 LAST VALUE 1
J 2
(-7275 5500);
DISPLAY 0.489362 (-7275 5500);
PAINT SKYBLUE (-7275 5500);
FORCEPROP 1 LAST TOLERANCE 1%
J 0
(-7075 5525);
DISPLAY 0.489362 (-7075 5525);
PAINT SKYBLUE (-7075 5525);
FORCEPROP 1 LAST MATERIAL CHIP
J 0
(-7175 5375);
DISPLAY 0.489362 (-7175 5375);
PAINT SKYBLUE (-7175 5375);
FORCEPROP 1 LAST WATTAGE 1/10W
J 2
(-7200 5400);
DISPLAY 0.489362 (-7200 5400);
PAINT SKYBLUE (-7200 5400);
FORCEPROP 1 LAST PART_NUMBER CS-1003F920
J 0
(-7250 5575);
DISPLAY 0.978723 (-7250 5575);
PAINT SKYBLUE (-7250 5575);
DISPLAY INVISIBLE (-7250 5575);
FORCEPROP 1 LAST PATH I44
J 0
(-7250 5625);
DISPLAY 0.978723 (-7250 5625);
PAINT WHITE (-7250 5625);
DISPLAY INVISIBLE (-7250 5625);
FORCEPROP 2 LAST CDS_LIB pure_quanta
J 0
(-7200 5475);
DISPLAY INVISIBLE (-7200 5475);
FORCEADD UNIVERSAL_GND..1
(-6250 5050);
FORCEPROP 3 LASTPIN (-6250 5100) SIG_NAME GND\g
J 0
(-6240 5110);
DISPLAY 0.659574 (-6240 5110);
PAINT MONO (-6240 5110);
DISPLAY INVISIBLE (-6240 5110);
FORCEPROP 1 LAST HDL_POWER GND
J 1
(-6225 4975);
DISPLAY 0.489362 (-6225 4975);
PAINT GREEN (-6225 4975);
FORCEPROP 1 LAST PATH I45
J 0
(-6175 5050);
DISPLAY 0.872340 (-6175 5050);
PAINT AQUA (-6175 5050);
DISPLAY INVISIBLE (-6175 5050);
FORCEPROP 2 LAST CDS_LIB pure_quanta_power
J 0
(-6250 5050);
DISPLAY INVISIBLE (-6250 5050);
FORCEADD UNIVERSAL_GND..1
(-6450 5050);
FORCEPROP 3 LASTPIN (-6450 5100) SIG_NAME GND\g
J 0
(-6440 5110);
DISPLAY 0.659574 (-6440 5110);
PAINT MONO (-6440 5110);
DISPLAY INVISIBLE (-6440 5110);
FORCEPROP 1 LAST HDL_POWER GND
J 1
(-6425 4975);
DISPLAY 0.489362 (-6425 4975);
PAINT GREEN (-6425 4975);
FORCEPROP 1 LAST PATH I46
J 0
(-6375 5050);
DISPLAY 0.872340 (-6375 5050);
PAINT AQUA (-6375 5050);
DISPLAY INVISIBLE (-6375 5050);
FORCEPROP 2 LAST CDS_LIB pure_quanta_power
J 0
(-6450 5050);
DISPLAY INVISIBLE (-6450 5050);
FORCEADD UNIVERSAL_GND..1
(-6700 5050);
FORCEPROP 3 LASTPIN (-6700 5100) SIG_NAME GND\g
J 0
(-6690 5110);
DISPLAY 0.659574 (-6690 5110);
PAINT MONO (-6690 5110);
DISPLAY INVISIBLE (-6690 5110);
FORCEPROP 1 LAST HDL_POWER GND
J 1
(-6675 4975);
DISPLAY 0.489362 (-6675 4975);
PAINT GREEN (-6675 4975);
FORCEPROP 1 LAST PATH I47
J 0
(-6625 5050);
DISPLAY 0.872340 (-6625 5050);
PAINT AQUA (-6625 5050);
DISPLAY INVISIBLE (-6625 5050);
FORCEPROP 2 LAST CDS_LIB pure_quanta_power
J 0
(-6700 5050);
DISPLAY INVISIBLE (-6700 5050);
FORCEADD Q_CAP..1
(-7365 4790);
FORCEPROP 1 LAST LOCATION C1230
J 0
(-7300 4895);
DISPLAY 0.489362 (-7300 4895);
PAINT SKYBLUE (-7300 4895);
FORCEPROP 0 LAST $SEC 1
J 0
(-7300 4950);
DISPLAY 0.680851 (-7300 4950);
PAINT MONO (-7300 4950);
DISPLAY INVISIBLE (-7300 4950);
FORCEPROP 0 LAST CDS_SEC 1
J 0
(-7300 4950);
DISPLAY 1.021277 (-7300 4950);
DISPLAY INVISIBLE (-7300 4950);
FORCEPROP 1 LASTPIN (-7365 4890) $PN 1
J 0
(-7355 4870);
DISPLAY 0.489362 (-7355 4870);
PAINT MONO (-7355 4870);
FORCEPROP 1 LASTPIN (-7365 4690) $PN 2
J 0
(-7355 4670);
DISPLAY 0.489362 (-7355 4670);
PAINT MONO (-7355 4670);
FORCEPROP 1 LAST PACK_TYPE 0402
J 0
(-7315 4640);
DISPLAY 0.489362 (-7315 4640);
PAINT SKYBLUE (-7315 4640);
FORCEPROP 1 LAST VOLTAGE 25V
J 0
(-7315 4790);
DISPLAY 0.489362 (-7315 4790);
PAINT SKYBLUE (-7315 4790);
FORCEPROP 1 LAST VALUE 0.1UF
J 0
(-7300 4845);
DISPLAY 0.489362 (-7300 4845);
PAINT SKYBLUE (-7300 4845);
FORCEPROP 1 LAST TOLERANCE 10%
J 0
(-7315 4740);
DISPLAY 0.489362 (-7315 4740);
PAINT SKYBLUE (-7315 4740);
FORCEPROP 1 LAST MATERIAL X7R
J 0
(-7315 4690);
DISPLAY 0.489362 (-7315 4690);
PAINT SKYBLUE (-7315 4690);
FORCEPROP 1 LAST PART_NUMBER CH4104K1B00
J 0
(-7315 4640);
DISPLAY 0.978723 (-7315 4640);
PAINT SKYBLUE (-7315 4640);
DISPLAY INVISIBLE (-7315 4640);
FORCEPROP 1 LAST PATH I49
J 0
(-7315 4940);
DISPLAY 0.978723 (-7315 4940);
PAINT WHITE (-7315 4940);
DISPLAY INVISIBLE (-7315 4940);
FORCEPROP 2 LAST CDS_LIB pure_quanta
J 0
(-7365 4790);
DISPLAY INVISIBLE (-7365 4790);
FORCEADD UNIVERSAL_GND..1
(-7365 4515);
FORCEPROP 3 LASTPIN (-7365 4565) SIG_NAME GND\g
J 0
(-7355 4575);
DISPLAY 0.659574 (-7355 4575);
PAINT MONO (-7355 4575);
DISPLAY INVISIBLE (-7355 4575);
FORCEPROP 1 LAST HDL_POWER GND
J 1
(-7340 4440);
DISPLAY 0.489362 (-7340 4440);
PAINT GREEN (-7340 4440);
FORCEPROP 1 LAST PATH I51
J 0
(-7290 4515);
DISPLAY 0.872340 (-7290 4515);
PAINT AQUA (-7290 4515);
DISPLAY INVISIBLE (-7290 4515);
FORCEPROP 2 LAST CDS_LIB pure_quanta_power
J 0
(-7365 4515);
DISPLAY INVISIBLE (-7365 4515);
FORCEADD UNIVERSAL_POWER..1
(-7550 5675);
FORCEPROP 3 LASTPIN (-7550 5625) SIG_NAME P3V3_9ZX_VDD_2\g
J 0
(-7540 5635);
DISPLAY 0.659574 (-7540 5635);
PAINT MONO (-7540 5635);
DISPLAY INVISIBLE (-7540 5635);
FORCEPROP 1 LAST HDL_POWER P3V3_9ZX_VDD_2
J 1
(-7550 5725);
DISPLAY 0.489362 (-7550 5725);
PAINT GREEN (-7550 5725);
FORCEPROP 2 LAST ROOM DB2000_1_BCLK
J 0
(-7550 5775);
DISPLAY 0.808511 (-7550 5775);
PAINT RED (-7550 5775);
DISPLAY INVISIBLE (-7550 5775);
FORCEPROP 0 LAST VOLTAGE 3.3
J 0
(-7550 5825);
DISPLAY 1.021277 (-7550 5825);
PAINT SKYBLUE (-7550 5825);
DISPLAY INVISIBLE (-7550 5825);
FORCEPROP 1 LAST PATH I52
J 0
(-7500 5700);
DISPLAY 0.872340 (-7500 5700);
PAINT AQUA (-7500 5700);
DISPLAY INVISIBLE (-7500 5700);
FORCEPROP 2 LAST CDS_LIB mstr_symbols
J 0
(-7550 5675);
DISPLAY INVISIBLE (-7550 5675);
FORCEPROP 2 LAST BOM_COST SYS_CLOCK
J 0
(-7550 5825);
DISPLAY 0.808511 (-7550 5825);
DISPLAY INVISIBLE (-7550 5825);
FORCEADD UNIVERSAL_POWER..1
(-9225 5625);
FORCEPROP 3 LASTPIN (-9225 5575) SIG_NAME P3V3\g
J 0
(-9215 5585);
DISPLAY 0.659574 (-9215 5585);
PAINT MONO (-9215 5585);
DISPLAY INVISIBLE (-9215 5585);
FORCEPROP 1 LAST HDL_POWER P3V3
J 1
(-9225 5675);
DISPLAY 0.489362 (-9225 5675);
PAINT GREEN (-9225 5675);
FORCEPROP 1 LAST PATH I57
J 0
(-9175 5650);
DISPLAY 0.872340 (-9175 5650);
PAINT AQUA (-9175 5650);
DISPLAY INVISIBLE (-9175 5650);
FORCEPROP 2 LAST CDS_LIB pure_quanta_power
J 0
(-9225 5625);
DISPLAY INVISIBLE (-9225 5625);
FORCEADD Q_INDUCTOR..1
(-8875 5500);
FORCEPROP 1 LAST LOCATION L8
J 0
(-9000 5660);
DISPLAY 0.489362 (-9000 5660);
PAINT SKYBLUE (-9000 5660);
FORCEPROP 0 LAST $SEC 1
J 0
(-9000 5775);
DISPLAY 0.680851 (-9000 5775);
PAINT MONO (-9000 5775);
DISPLAY INVISIBLE (-9000 5775);
FORCEPROP 0 LAST CDS_SEC 1
J 0
(-9000 5775);
DISPLAY 1.021277 (-9000 5775);
DISPLAY INVISIBLE (-9000 5775);
FORCEPROP 0 LASTPIN (-8975 5475) $PN 1
J 2
(-8985 5485);
DISPLAY 0.489362 (-8985 5485);
PAINT MONO (-8985 5485);
FORCEPROP 0 LASTPIN (-8775 5475) $PN 2
J 0
(-8765 5485);
DISPLAY 0.489362 (-8765 5485);
PAINT MONO (-8765 5485);
FORCEPROP 2 LAST PACK_TYPE SMLF
J 0
(-9000 5750);
DISPLAY 0.489362 (-9000 5750);
PAINT SKYBLUE (-9000 5750);
FORCEPROP 1 LAST PART_NUMBER CX12S331000
J 0
(-9000 5610);
DISPLAY 0.489362 (-9000 5610);
PAINT SKYBLUE (-9000 5610);
FORCEPROP 2 LAST VALUE 330/2.5A
J 0
(-9000 5700);
DISPLAY 0.489362 (-9000 5700);
PAINT SKYBLUE (-9000 5700);
FORCEPROP 1 LAST MATERIAL IND
J 0
(-9000 5555);
DISPLAY 0.489362 (-9000 5555);
PAINT SKYBLUE (-9000 5555);
FORCEPROP 1 LAST PATH I58
J 0
(-8800 5555);
DISPLAY 0.723404 (-8800 5555);
PAINT GREEN (-8800 5555);
DISPLAY INVISIBLE (-8800 5555);
FORCEPROP 2 LAST CDS_LIB pure_quanta
J 0
(-8875 5500);
DISPLAY INVISIBLE (-8875 5500);
FORCEPROP 1 LAST NEEDS_NO_SIZE TRUE
J 0
(-8875 5500);
DISPLAY 0.468085 (-8875 5500);
PAINT GREEN (-8875 5500);
DISPLAY INVISIBLE (-8875 5500);
FORCEADD Q_CAP..1
(-7595 4795);
FORCEPROP 1 LAST LOCATION C1229
J 0
(-7545 4895);
DISPLAY 0.489362 (-7545 4895);
PAINT SKYBLUE (-7545 4895);
FORCEPROP 0 LAST $SEC 1
J 0
(-7525 4950);
DISPLAY 0.680851 (-7525 4950);
PAINT MONO (-7525 4950);
DISPLAY INVISIBLE (-7525 4950);
FORCEPROP 0 LAST CDS_SEC 1
J 0
(-7525 4950);
DISPLAY 1.021277 (-7525 4950);
DISPLAY INVISIBLE (-7525 4950);
FORCEPROP 1 LASTPIN (-7595 4895) $PN 1
J 0
(-7585 4875);
DISPLAY 0.489362 (-7585 4875);
PAINT MONO (-7585 4875);
FORCEPROP 1 LASTPIN (-7595 4695) $PN 2
J 0
(-7585 4675);
DISPLAY 0.489362 (-7585 4675);
PAINT MONO (-7585 4675);
FORCEPROP 1 LAST PACK_TYPE 0402
J 0
(-7545 4645);
DISPLAY 0.489362 (-7545 4645);
PAINT SKYBLUE (-7545 4645);
FORCEPROP 1 LAST VOLTAGE 25V
J 0
(-7545 4795);
DISPLAY 0.489362 (-7545 4795);
PAINT SKYBLUE (-7545 4795);
FORCEPROP 1 LAST VALUE 0.1UF
J 0
(-7545 4845);
DISPLAY 0.489362 (-7545 4845);
PAINT SKYBLUE (-7545 4845);
FORCEPROP 1 LAST TOLERANCE 10%
J 0
(-7545 4745);
DISPLAY 0.489362 (-7545 4745);
PAINT SKYBLUE (-7545 4745);
FORCEPROP 1 LAST MATERIAL X7R
J 0
(-7545 4695);
DISPLAY 0.489362 (-7545 4695);
PAINT SKYBLUE (-7545 4695);
FORCEPROP 1 LAST PART_NUMBER CH4104K1B00
J 0
(-7545 4645);
DISPLAY 0.978723 (-7545 4645);
PAINT SKYBLUE (-7545 4645);
DISPLAY INVISIBLE (-7545 4645);
FORCEPROP 1 LAST PATH I59
J 0
(-7545 4945);
DISPLAY 0.978723 (-7545 4945);
PAINT WHITE (-7545 4945);
DISPLAY INVISIBLE (-7545 4945);
FORCEPROP 2 LAST CDS_LIB pure_quanta
J 0
(-7595 4795);
DISPLAY INVISIBLE (-7595 4795);
FORCEADD Q_CAP..1
(-7825 4800);
FORCEPROP 1 LAST LOCATION C1228
J 0
(-7775 4900);
DISPLAY 0.489362 (-7775 4900);
PAINT SKYBLUE (-7775 4900);
FORCEPROP 0 LAST $SEC 1
J 0
(-7775 4950);
DISPLAY 0.680851 (-7775 4950);
PAINT MONO (-7775 4950);
DISPLAY INVISIBLE (-7775 4950);
FORCEPROP 0 LAST CDS_SEC 1
J 0
(-7775 4950);
DISPLAY 1.021277 (-7775 4950);
DISPLAY INVISIBLE (-7775 4950);
FORCEPROP 1 LASTPIN (-7825 4900) $PN 1
J 0
(-7815 4880);
DISPLAY 0.489362 (-7815 4880);
PAINT MONO (-7815 4880);
FORCEPROP 1 LASTPIN (-7825 4700) $PN 2
J 0
(-7815 4680);
DISPLAY 0.489362 (-7815 4680);
PAINT MONO (-7815 4680);
FORCEPROP 1 LAST PACK_TYPE 0402
J 0
(-7775 4650);
DISPLAY 0.489362 (-7775 4650);
PAINT SKYBLUE (-7775 4650);
FORCEPROP 1 LAST VOLTAGE 25V
J 0
(-7775 4800);
DISPLAY 0.489362 (-7775 4800);
PAINT SKYBLUE (-7775 4800);
FORCEPROP 1 LAST VALUE 0.1UF
J 0
(-7775 4850);
DISPLAY 0.489362 (-7775 4850);
PAINT SKYBLUE (-7775 4850);
FORCEPROP 1 LAST TOLERANCE 10%
J 0
(-7775 4750);
DISPLAY 0.489362 (-7775 4750);
PAINT SKYBLUE (-7775 4750);
FORCEPROP 1 LAST MATERIAL X7R
J 0
(-7775 4700);
DISPLAY 0.489362 (-7775 4700);
PAINT SKYBLUE (-7775 4700);
FORCEPROP 1 LAST PART_NUMBER CH4104K1B00
J 0
(-7775 4650);
DISPLAY 0.978723 (-7775 4650);
PAINT SKYBLUE (-7775 4650);
DISPLAY INVISIBLE (-7775 4650);
FORCEPROP 1 LAST PATH I61
J 0
(-7775 4950);
DISPLAY 0.978723 (-7775 4950);
PAINT WHITE (-7775 4950);
DISPLAY INVISIBLE (-7775 4950);
FORCEPROP 2 LAST CDS_LIB pure_quanta
J 0
(-7825 4800);
DISPLAY INVISIBLE (-7825 4800);
FORCEADD UNIVERSAL_GND..1
(-7595 4520);
FORCEPROP 3 LASTPIN (-7595 4570) SIG_NAME GND\g
J 0
(-7585 4580);
DISPLAY 0.659574 (-7585 4580);
PAINT MONO (-7585 4580);
DISPLAY INVISIBLE (-7585 4580);
FORCEPROP 1 LAST HDL_POWER GND
J 1
(-7570 4445);
DISPLAY 0.489362 (-7570 4445);
PAINT GREEN (-7570 4445);
FORCEPROP 1 LAST PATH I62
J 0
(-7520 4520);
DISPLAY 0.872340 (-7520 4520);
PAINT AQUA (-7520 4520);
DISPLAY INVISIBLE (-7520 4520);
FORCEPROP 2 LAST CDS_LIB pure_quanta_power
J 0
(-7595 4520);
DISPLAY INVISIBLE (-7595 4520);
FORCEADD UNIVERSAL_GND..1
(-7825 4525);
FORCEPROP 3 LASTPIN (-7825 4575) SIG_NAME GND\g
J 0
(-7815 4585);
DISPLAY 0.659574 (-7815 4585);
PAINT MONO (-7815 4585);
DISPLAY INVISIBLE (-7815 4585);
FORCEPROP 1 LAST HDL_POWER GND
J 1
(-7800 4450);
DISPLAY 0.489362 (-7800 4450);
PAINT GREEN (-7800 4450);
FORCEPROP 1 LAST PATH I63
J 0
(-7750 4525);
DISPLAY 0.872340 (-7750 4525);
PAINT AQUA (-7750 4525);
DISPLAY INVISIBLE (-7750 4525);
FORCEPROP 2 LAST CDS_LIB pure_quanta_power
J 0
(-7825 4525);
DISPLAY INVISIBLE (-7825 4525);
FORCEADD Q_CAP..1
(-8050 4800);
FORCEPROP 1 LAST LOCATION C1226
J 0
(-8000 4900);
DISPLAY 0.489362 (-8000 4900);
PAINT SKYBLUE (-8000 4900);
FORCEPROP 0 LAST $SEC 1
J 0
(-8000 4950);
DISPLAY 0.680851 (-8000 4950);
PAINT MONO (-8000 4950);
DISPLAY INVISIBLE (-8000 4950);
FORCEPROP 0 LAST CDS_SEC 1
J 0
(-8000 4950);
DISPLAY 1.021277 (-8000 4950);
DISPLAY INVISIBLE (-8000 4950);
FORCEPROP 1 LASTPIN (-8050 4900) $PN 1
J 0
(-8040 4880);
DISPLAY 0.489362 (-8040 4880);
PAINT MONO (-8040 4880);
FORCEPROP 1 LASTPIN (-8050 4700) $PN 2
J 0
(-8040 4680);
DISPLAY 0.489362 (-8040 4680);
PAINT MONO (-8040 4680);
FORCEPROP 1 LAST PACK_TYPE 0402
J 0
(-8000 4650);
DISPLAY 0.489362 (-8000 4650);
PAINT SKYBLUE (-8000 4650);
FORCEPROP 1 LAST VOLTAGE 25V
J 0
(-8000 4800);
DISPLAY 0.489362 (-8000 4800);
PAINT SKYBLUE (-8000 4800);
FORCEPROP 1 LAST VALUE 0.1UF
J 0
(-8000 4850);
DISPLAY 0.489362 (-8000 4850);
PAINT SKYBLUE (-8000 4850);
FORCEPROP 1 LAST TOLERANCE 10%
J 0
(-8000 4750);
DISPLAY 0.489362 (-8000 4750);
PAINT SKYBLUE (-8000 4750);
FORCEPROP 1 LAST MATERIAL X7R
J 0
(-8000 4700);
DISPLAY 0.489362 (-8000 4700);
PAINT SKYBLUE (-8000 4700);
FORCEPROP 1 LAST PART_NUMBER CH4104K1B00
J 0
(-8000 4650);
DISPLAY 0.978723 (-8000 4650);
PAINT SKYBLUE (-8000 4650);
DISPLAY INVISIBLE (-8000 4650);
FORCEPROP 1 LAST PATH I65
J 0
(-8000 4950);
DISPLAY 0.978723 (-8000 4950);
PAINT WHITE (-8000 4950);
DISPLAY INVISIBLE (-8000 4950);
FORCEPROP 2 LAST CDS_LIB pure_quanta
J 0
(-8050 4800);
DISPLAY INVISIBLE (-8050 4800);
FORCEADD Q_CAP..1
(-8300 4800);
FORCEPROP 1 LAST LOCATION C1224
J 0
(-8250 4900);
DISPLAY 0.489362 (-8250 4900);
PAINT SKYBLUE (-8250 4900);
FORCEPROP 0 LAST $SEC 1
J 0
(-8250 4950);
DISPLAY 0.680851 (-8250 4950);
PAINT MONO (-8250 4950);
DISPLAY INVISIBLE (-8250 4950);
FORCEPROP 0 LAST CDS_SEC 1
J 0
(-8250 4950);
DISPLAY 1.021277 (-8250 4950);
DISPLAY INVISIBLE (-8250 4950);
FORCEPROP 1 LASTPIN (-8300 4900) $PN 1
J 0
(-8290 4880);
DISPLAY 0.489362 (-8290 4880);
PAINT MONO (-8290 4880);
FORCEPROP 1 LASTPIN (-8300 4700) $PN 2
J 0
(-8290 4680);
DISPLAY 0.489362 (-8290 4680);
PAINT MONO (-8290 4680);
FORCEPROP 1 LAST PACK_TYPE 0402
J 0
(-8250 4650);
DISPLAY 0.489362 (-8250 4650);
PAINT SKYBLUE (-8250 4650);
FORCEPROP 1 LAST VOLTAGE 25V
J 0
(-8250 4800);
DISPLAY 0.489362 (-8250 4800);
PAINT SKYBLUE (-8250 4800);
FORCEPROP 1 LAST VALUE 0.1UF
J 0
(-8250 4850);
DISPLAY 0.489362 (-8250 4850);
PAINT SKYBLUE (-8250 4850);
FORCEPROP 1 LAST TOLERANCE 10%
J 0
(-8250 4750);
DISPLAY 0.489362 (-8250 4750);
PAINT SKYBLUE (-8250 4750);
FORCEPROP 1 LAST MATERIAL X7R
J 0
(-8250 4700);
DISPLAY 0.489362 (-8250 4700);
PAINT SKYBLUE (-8250 4700);
FORCEPROP 1 LAST PART_NUMBER CH4104K1B00
J 0
(-8250 4650);
DISPLAY 0.978723 (-8250 4650);
PAINT SKYBLUE (-8250 4650);
DISPLAY INVISIBLE (-8250 4650);
FORCEPROP 1 LAST PATH I67
J 0
(-8250 4950);
DISPLAY 0.978723 (-8250 4950);
PAINT WHITE (-8250 4950);
DISPLAY INVISIBLE (-8250 4950);
FORCEPROP 2 LAST CDS_LIB pure_quanta
J 0
(-8300 4800);
DISPLAY INVISIBLE (-8300 4800);
FORCEADD UNIVERSAL_GND..1
(-8050 4525);
FORCEPROP 3 LASTPIN (-8050 4575) SIG_NAME GND\g
J 0
(-8040 4585);
DISPLAY 0.659574 (-8040 4585);
PAINT MONO (-8040 4585);
DISPLAY INVISIBLE (-8040 4585);
FORCEPROP 1 LAST HDL_POWER GND
J 1
(-8025 4450);
DISPLAY 0.489362 (-8025 4450);
PAINT GREEN (-8025 4450);
FORCEPROP 1 LAST PATH I68
J 0
(-7975 4525);
DISPLAY 0.872340 (-7975 4525);
PAINT AQUA (-7975 4525);
DISPLAY INVISIBLE (-7975 4525);
FORCEPROP 2 LAST CDS_LIB pure_quanta_power
J 0
(-8050 4525);
DISPLAY INVISIBLE (-8050 4525);
FORCEADD UNIVERSAL_GND..1
(-8300 4525);
FORCEPROP 3 LASTPIN (-8300 4575) SIG_NAME GND\g
J 0
(-8290 4585);
DISPLAY 0.659574 (-8290 4585);
PAINT MONO (-8290 4585);
DISPLAY INVISIBLE (-8290 4585);
FORCEPROP 1 LAST HDL_POWER GND
J 1
(-8275 4450);
DISPLAY 0.489362 (-8275 4450);
PAINT GREEN (-8275 4450);
FORCEPROP 1 LAST PATH I69
J 0
(-8225 4525);
DISPLAY 0.872340 (-8225 4525);
PAINT AQUA (-8225 4525);
DISPLAY INVISIBLE (-8225 4525);
FORCEPROP 2 LAST CDS_LIB pure_quanta_power
J 0
(-8300 4525);
DISPLAY INVISIBLE (-8300 4525);
FORCEADD Q_CAP..1
(-8700 4835);
FORCEPROP 1 LAST LOCATION C1221
J 0
(-8650 4935);
DISPLAY 0.489362 (-8650 4935);
PAINT SKYBLUE (-8650 4935);
FORCEPROP 0 LAST $SEC 1
J 0
(-8650 5000);
DISPLAY 0.680851 (-8650 5000);
PAINT MONO (-8650 5000);
DISPLAY INVISIBLE (-8650 5000);
FORCEPROP 0 LAST CDS_SEC 1
J 0
(-8650 5000);
DISPLAY 1.021277 (-8650 5000);
DISPLAY INVISIBLE (-8650 5000);
FORCEPROP 1 LASTPIN (-8700 4935) $PN 1
J 0
(-8690 4915);
DISPLAY 0.489362 (-8690 4915);
PAINT MONO (-8690 4915);
FORCEPROP 1 LASTPIN (-8700 4735) $PN 2
J 0
(-8690 4715);
DISPLAY 0.489362 (-8690 4715);
PAINT MONO (-8690 4715);
FORCEPROP 1 LAST PACK_TYPE C0402
J 0
(-8650 4685);
DISPLAY 0.489362 (-8650 4685);
PAINT SKYBLUE (-8650 4685);
FORCEPROP 1 LAST VOLTAGE 25V
J 0
(-8650 4835);
DISPLAY 0.489362 (-8650 4835);
PAINT SKYBLUE (-8650 4835);
FORCEPROP 1 LAST VALUE 1UF
J 0
(-8650 4885);
DISPLAY 0.489362 (-8650 4885);
PAINT SKYBLUE (-8650 4885);
FORCEPROP 1 LAST TOLERANCE 10%
J 0
(-8650 4785);
DISPLAY 0.489362 (-8650 4785);
PAINT SKYBLUE (-8650 4785);
FORCEPROP 1 LAST MATERIAL X6S
J 0
(-8650 4735);
DISPLAY 0.489362 (-8650 4735);
PAINT SKYBLUE (-8650 4735);
FORCEPROP 1 LAST PART_NUMBER CH5104KEB02
J 0
(-8650 4685);
DISPLAY 0.617021 (-8650 4685);
PAINT SKYBLUE (-8650 4685);
DISPLAY INVISIBLE (-8650 4685);
FORCEPROP 1 LAST PATH I71
J 0
(-8650 4985);
DISPLAY 0.978723 (-8650 4985);
PAINT WHITE (-8650 4985);
DISPLAY INVISIBLE (-8650 4985);
FORCEPROP 2 LAST CDS_LIB pure_quanta
J 0
(-8700 4835);
DISPLAY INVISIBLE (-8700 4835);
FORCEADD UNIVERSAL_GND..1
(-8700 4550);
FORCEPROP 3 LASTPIN (-8700 4600) SIG_NAME GND\g
J 0
(-8690 4610);
DISPLAY 0.659574 (-8690 4610);
PAINT MONO (-8690 4610);
DISPLAY INVISIBLE (-8690 4610);
FORCEPROP 1 LAST HDL_POWER GND
J 1
(-8675 4475);
DISPLAY 0.489362 (-8675 4475);
PAINT GREEN (-8675 4475);
FORCEPROP 1 LAST PATH I72
J 0
(-8625 4550);
DISPLAY 0.872340 (-8625 4550);
PAINT AQUA (-8625 4550);
DISPLAY INVISIBLE (-8625 4550);
FORCEPROP 2 LAST CDS_LIB pure_quanta_power
J 0
(-8700 4550);
DISPLAY INVISIBLE (-8700 4550);
FORCEADD OFFPAGE..2
(-800 5275);
FORCEPROP 2 LAST $XR0 116 
J 0
(-611 5275);
DISPLAY 0.638298 (-611 5275);
PAINT MONO (-611 5275);
FORCEPROP 2 LAST PATH I73
J 0
(-600 5325);
DISPLAY 1.021277 (-600 5325);
DISPLAY INVISIBLE (-600 5325);
FORCEPROP 1 LAST COMMENT_BODY TRUE
J 0
(-845 5180);
DISPLAY 0.872340 (-845 5180);
PAINT GREEN (-845 5180);
DISPLAY INVISIBLE (-845 5180);
FORCEPROP 1 LAST OFFPAGE TRUE
J 0
(-475 5150);
DISPLAY 0.723404 (-475 5150);
PAINT GREEN (-475 5150);
DISPLAY INVISIBLE (-475 5150);
FORCEPROP 2 LAST CDS_LIB standard
J 0
(-800 5275);
DISPLAY INVISIBLE (-800 5275);
FORCEADD OFFPAGE..2
(-800 5225);
FORCEPROP 2 LAST $XR0 116 
J 0
(-611 5225);
DISPLAY 0.638298 (-611 5225);
PAINT MONO (-611 5225);
FORCEPROP 2 LAST PATH I74
J 0
(-600 5275);
DISPLAY 1.021277 (-600 5275);
DISPLAY INVISIBLE (-600 5275);
FORCEPROP 1 LAST COMMENT_BODY TRUE
J 0
(-845 5130);
DISPLAY 0.872340 (-845 5130);
PAINT GREEN (-845 5130);
DISPLAY INVISIBLE (-845 5130);
FORCEPROP 1 LAST OFFPAGE TRUE
J 0
(-475 5100);
DISPLAY 0.723404 (-475 5100);
PAINT GREEN (-475 5100);
DISPLAY INVISIBLE (-475 5100);
FORCEPROP 2 LAST CDS_LIB standard
J 0
(-800 5225);
DISPLAY INVISIBLE (-800 5225);
FORCEADD OFFPAGE..2
(-800 5175);
FORCEPROP 2 LAST $XR0 119 
J 0
(-611 5175);
DISPLAY 0.638298 (-611 5175);
PAINT MONO (-611 5175);
FORCEPROP 2 LAST PATH I75
J 0
(-600 5225);
DISPLAY 1.021277 (-600 5225);
DISPLAY INVISIBLE (-600 5225);
FORCEPROP 1 LAST COMMENT_BODY TRUE
J 0
(-845 5080);
DISPLAY 0.872340 (-845 5080);
PAINT GREEN (-845 5080);
DISPLAY INVISIBLE (-845 5080);
FORCEPROP 1 LAST OFFPAGE TRUE
J 0
(-475 5050);
DISPLAY 0.723404 (-475 5050);
PAINT GREEN (-475 5050);
DISPLAY INVISIBLE (-475 5050);
FORCEPROP 2 LAST CDS_LIB standard
J 0
(-800 5175);
DISPLAY INVISIBLE (-800 5175);
FORCEADD OFFPAGE..2
(-800 5125);
FORCEPROP 2 LAST $XR0 119 
J 0
(-611 5125);
DISPLAY 0.638298 (-611 5125);
PAINT MONO (-611 5125);
FORCEPROP 2 LAST PATH I76
J 0
(-600 5175);
DISPLAY 1.021277 (-600 5175);
DISPLAY INVISIBLE (-600 5175);
FORCEPROP 1 LAST COMMENT_BODY TRUE
J 0
(-845 5030);
DISPLAY 0.872340 (-845 5030);
PAINT GREEN (-845 5030);
DISPLAY INVISIBLE (-845 5030);
FORCEPROP 1 LAST OFFPAGE TRUE
J 0
(-475 5000);
DISPLAY 0.723404 (-475 5000);
PAINT GREEN (-475 5000);
DISPLAY INVISIBLE (-475 5000);
FORCEPROP 2 LAST CDS_LIB standard
J 0
(-800 5125);
DISPLAY INVISIBLE (-800 5125);
FORCEADD Q_RES..1
(-1700 5275);
FORCEPROP 1 LAST LOCATION R2292
J 0
(-1900 5275);
DISPLAY 0.489362 (-1900 5275);
PAINT SKYBLUE (-1900 5275);
FORCEPROP 0 LAST $SEC 1
J 0
(-1775 5325);
DISPLAY 0.680851 (-1775 5325);
PAINT MONO (-1775 5325);
DISPLAY INVISIBLE (-1775 5325);
FORCEPROP 0 LAST CDS_SEC 1
J 0
(-1775 5325);
DISPLAY 1.021277 (-1775 5325);
DISPLAY INVISIBLE (-1775 5325);
FORCEPROP 1 LASTPIN (-1800 5275) $PN 1
J 0
(-1788 5287);
DISPLAY 0.489362 (-1788 5287);
PAINT MONO (-1788 5287);
FORCEPROP 1 LASTPIN (-1600 5275) $PN 2
J 0
(-1638 5287);
DISPLAY 0.489362 (-1638 5287);
PAINT MONO (-1638 5287);
FORCEPROP 1 LAST VALUE 0
J 2
(-1575 5275);
DISPLAY 0.489362 (-1575 5275);
PAINT SKYBLUE (-1575 5275);
FORCEPROP 1 LAST PACK_TYPE 0402LF
J 0
(-1650 5200);
DISPLAY 0.489362 (-1650 5200);
PAINT SKYBLUE (-1650 5200);
DISPLAY INVISIBLE (-1650 5200);
FORCEPROP 1 LAST PART_NUMBER CS00002JB38
J 0
(-1675 5325);
DISPLAY 0.489362 (-1675 5325);
PAINT SKYBLUE (-1675 5325);
DISPLAY INVISIBLE (-1675 5325);
FORCEPROP 1 LAST TOLERANCE 5%
J 0
(-1725 5200);
DISPLAY 0.489362 (-1725 5200);
PAINT SKYBLUE (-1725 5200);
DISPLAY INVISIBLE (-1725 5200);
FORCEPROP 1 LAST MATERIAL CHIP
J 0
(-1275 5200);
DISPLAY 0.489362 (-1275 5200);
PAINT SKYBLUE (-1275 5200);
DISPLAY INVISIBLE (-1275 5200);
FORCEPROP 1 LAST WATTAGE 1/16W
J 2
(-1300 5200);
DISPLAY 0.489362 (-1300 5200);
PAINT SKYBLUE (-1300 5200);
DISPLAY INVISIBLE (-1300 5200);
FORCEPROP 1 LAST PATH I79
J 0
(-1750 5425);
DISPLAY 0.978723 (-1750 5425);
PAINT WHITE (-1750 5425);
DISPLAY INVISIBLE (-1750 5425);
FORCEPROP 2 LAST CDS_LIB pure_quanta
J 0
(-1700 5275);
DISPLAY INVISIBLE (-1700 5275);
FORCEADD Q_RES..1
(-1700 5225);
FORCEPROP 1 LAST LOCATION R2293
J 0
(-1900 5225);
DISPLAY 0.489362 (-1900 5225);
PAINT SKYBLUE (-1900 5225);
FORCEPROP 0 LAST $SEC 1
J 0
(-1775 5275);
DISPLAY 0.680851 (-1775 5275);
PAINT MONO (-1775 5275);
DISPLAY INVISIBLE (-1775 5275);
FORCEPROP 0 LAST CDS_SEC 1
J 0
(-1775 5275);
DISPLAY 1.021277 (-1775 5275);
DISPLAY INVISIBLE (-1775 5275);
FORCEPROP 1 LASTPIN (-1800 5225) $PN 1
J 0
(-1788 5237);
DISPLAY 0.489362 (-1788 5237);
PAINT MONO (-1788 5237);
FORCEPROP 1 LASTPIN (-1600 5225) $PN 2
J 0
(-1638 5237);
DISPLAY 0.489362 (-1638 5237);
PAINT MONO (-1638 5237);
FORCEPROP 1 LAST VALUE 0
J 2
(-1575 5225);
DISPLAY 0.489362 (-1575 5225);
PAINT SKYBLUE (-1575 5225);
FORCEPROP 1 LAST PACK_TYPE 0402LF
J 0
(-1650 5150);
DISPLAY 0.489362 (-1650 5150);
PAINT SKYBLUE (-1650 5150);
DISPLAY INVISIBLE (-1650 5150);
FORCEPROP 1 LAST PART_NUMBER CS00002JB38
J 0
(-1675 5275);
DISPLAY 0.489362 (-1675 5275);
PAINT SKYBLUE (-1675 5275);
DISPLAY INVISIBLE (-1675 5275);
FORCEPROP 1 LAST TOLERANCE 5%
J 0
(-1725 5150);
DISPLAY 0.489362 (-1725 5150);
PAINT SKYBLUE (-1725 5150);
DISPLAY INVISIBLE (-1725 5150);
FORCEPROP 1 LAST MATERIAL CHIP
J 0
(-1275 5150);
DISPLAY 0.489362 (-1275 5150);
PAINT SKYBLUE (-1275 5150);
DISPLAY INVISIBLE (-1275 5150);
FORCEPROP 1 LAST WATTAGE 1/16W
J 2
(-1300 5150);
DISPLAY 0.489362 (-1300 5150);
PAINT SKYBLUE (-1300 5150);
DISPLAY INVISIBLE (-1300 5150);
FORCEPROP 1 LAST PATH I80
J 0
(-1750 5375);
DISPLAY 0.978723 (-1750 5375);
PAINT WHITE (-1750 5375);
DISPLAY INVISIBLE (-1750 5375);
FORCEPROP 2 LAST CDS_LIB pure_quanta
J 0
(-1700 5225);
DISPLAY INVISIBLE (-1700 5225);
FORCEADD Q_RES..1
(-1700 5175);
FORCEPROP 1 LAST LOCATION R2294
J 0
(-1900 5175);
DISPLAY 0.489362 (-1900 5175);
PAINT SKYBLUE (-1900 5175);
FORCEPROP 0 LAST $SEC 1
J 0
(-1775 5225);
DISPLAY 0.680851 (-1775 5225);
PAINT MONO (-1775 5225);
DISPLAY INVISIBLE (-1775 5225);
FORCEPROP 0 LAST CDS_SEC 1
J 0
(-1775 5225);
DISPLAY 1.021277 (-1775 5225);
DISPLAY INVISIBLE (-1775 5225);
FORCEPROP 1 LASTPIN (-1800 5175) $PN 1
J 0
(-1788 5187);
DISPLAY 0.489362 (-1788 5187);
PAINT MONO (-1788 5187);
FORCEPROP 1 LASTPIN (-1600 5175) $PN 2
J 0
(-1638 5187);
DISPLAY 0.489362 (-1638 5187);
PAINT MONO (-1638 5187);
FORCEPROP 1 LAST VALUE 0
J 2
(-1575 5175);
DISPLAY 0.489362 (-1575 5175);
PAINT SKYBLUE (-1575 5175);
FORCEPROP 1 LAST PACK_TYPE 0402LF
J 0
(-1650 5100);
DISPLAY 0.489362 (-1650 5100);
PAINT SKYBLUE (-1650 5100);
DISPLAY INVISIBLE (-1650 5100);
FORCEPROP 1 LAST PART_NUMBER CS00002JB38
J 0
(-1675 5225);
DISPLAY 0.489362 (-1675 5225);
PAINT SKYBLUE (-1675 5225);
DISPLAY INVISIBLE (-1675 5225);
FORCEPROP 1 LAST TOLERANCE 5%
J 0
(-1725 5100);
DISPLAY 0.489362 (-1725 5100);
PAINT SKYBLUE (-1725 5100);
DISPLAY INVISIBLE (-1725 5100);
FORCEPROP 1 LAST MATERIAL CHIP
J 0
(-1275 5100);
DISPLAY 0.489362 (-1275 5100);
PAINT SKYBLUE (-1275 5100);
DISPLAY INVISIBLE (-1275 5100);
FORCEPROP 1 LAST WATTAGE 1/16W
J 2
(-1300 5100);
DISPLAY 0.489362 (-1300 5100);
PAINT SKYBLUE (-1300 5100);
DISPLAY INVISIBLE (-1300 5100);
FORCEPROP 1 LAST PATH I81
J 0
(-1750 5325);
DISPLAY 0.978723 (-1750 5325);
PAINT WHITE (-1750 5325);
DISPLAY INVISIBLE (-1750 5325);
FORCEPROP 2 LAST CDS_LIB pure_quanta
J 0
(-1700 5175);
DISPLAY INVISIBLE (-1700 5175);
FORCEADD Q_RES..1
(-1700 5125);
FORCEPROP 1 LAST LOCATION R2295
J 0
(-1900 5125);
DISPLAY 0.489362 (-1900 5125);
PAINT SKYBLUE (-1900 5125);
FORCEPROP 0 LAST $SEC 1
J 0
(-1775 5175);
DISPLAY 0.680851 (-1775 5175);
PAINT MONO (-1775 5175);
DISPLAY INVISIBLE (-1775 5175);
FORCEPROP 0 LAST CDS_SEC 1
J 0
(-1775 5175);
DISPLAY 1.021277 (-1775 5175);
DISPLAY INVISIBLE (-1775 5175);
FORCEPROP 1 LASTPIN (-1800 5125) $PN 1
J 0
(-1788 5137);
DISPLAY 0.489362 (-1788 5137);
PAINT MONO (-1788 5137);
FORCEPROP 1 LASTPIN (-1600 5125) $PN 2
J 0
(-1638 5137);
DISPLAY 0.489362 (-1638 5137);
PAINT MONO (-1638 5137);
FORCEPROP 1 LAST VALUE 0
J 2
(-1575 5125);
DISPLAY 0.489362 (-1575 5125);
PAINT SKYBLUE (-1575 5125);
FORCEPROP 1 LAST PACK_TYPE 0402LF
J 0
(-1650 5050);
DISPLAY 0.489362 (-1650 5050);
PAINT SKYBLUE (-1650 5050);
DISPLAY INVISIBLE (-1650 5050);
FORCEPROP 1 LAST PART_NUMBER CS00002JB38
J 0
(-1675 5175);
DISPLAY 0.489362 (-1675 5175);
PAINT SKYBLUE (-1675 5175);
DISPLAY INVISIBLE (-1675 5175);
FORCEPROP 1 LAST TOLERANCE 5%
J 0
(-1725 5050);
DISPLAY 0.489362 (-1725 5050);
PAINT SKYBLUE (-1725 5050);
DISPLAY INVISIBLE (-1725 5050);
FORCEPROP 1 LAST MATERIAL CHIP
J 0
(-1275 5050);
DISPLAY 0.489362 (-1275 5050);
PAINT SKYBLUE (-1275 5050);
DISPLAY INVISIBLE (-1275 5050);
FORCEPROP 1 LAST WATTAGE 1/16W
J 2
(-1300 5050);
DISPLAY 0.489362 (-1300 5050);
PAINT SKYBLUE (-1300 5050);
DISPLAY INVISIBLE (-1300 5050);
FORCEPROP 1 LAST PATH I82
J 0
(-1750 5275);
DISPLAY 0.978723 (-1750 5275);
PAINT WHITE (-1750 5275);
DISPLAY INVISIBLE (-1750 5275);
FORCEPROP 2 LAST CDS_LIB pure_quanta
J 0
(-1700 5125);
DISPLAY INVISIBLE (-1700 5125);
FORCEADD UNIVERSAL_GND..1
(-1900 5425);
FORCEPROP 3 LASTPIN (-1900 5475) SIG_NAME GND\g
J 0
(-1890 5485);
DISPLAY 0.659574 (-1890 5485);
PAINT MONO (-1890 5485);
DISPLAY INVISIBLE (-1890 5485);
FORCEPROP 1 LAST HDL_POWER GND
J 1
(-1875 5350);
DISPLAY 0.489362 (-1875 5350);
PAINT GREEN (-1875 5350);
FORCEPROP 1 LAST PATH I85
J 0
(-1825 5425);
DISPLAY 0.872340 (-1825 5425);
PAINT AQUA (-1825 5425);
DISPLAY INVISIBLE (-1825 5425);
FORCEPROP 2 LAST CDS_LIB pure_quanta_power
J 0
(-1900 5425);
DISPLAY INVISIBLE (-1900 5425);
FORCEADD UNIVERSAL_POWER..1
(-1900 6125);
FORCEPROP 3 LASTPIN (-1900 6075) SIG_NAME P3V3\g
J 0
(-1890 6085);
DISPLAY 0.659574 (-1890 6085);
PAINT MONO (-1890 6085);
DISPLAY INVISIBLE (-1890 6085);
FORCEPROP 1 LAST HDL_POWER P3V3
J 1
(-1900 6175);
DISPLAY 0.489362 (-1900 6175);
PAINT GREEN (-1900 6175);
FORCEPROP 1 LAST PATH I86
J 0
(-1850 6150);
DISPLAY 0.872340 (-1850 6150);
PAINT AQUA (-1850 6150);
DISPLAY INVISIBLE (-1850 6150);
FORCEPROP 2 LAST CDS_LIB pure_quanta_power
J 0
(-1900 6125);
DISPLAY INVISIBLE (-1900 6125);
FORCEADD Q_RES..2
(-1900 5575);
FORCEPROP 1 LAST LOCATION R122
J 0
(-1855 5700);
DISPLAY 0.489362 (-1855 5700);
PAINT SKYBLUE (-1855 5700);
FORCEPROP 0 LAST $SEC 1
J 0
(-1850 5750);
DISPLAY 0.680851 (-1850 5750);
PAINT MONO (-1850 5750);
DISPLAY INVISIBLE (-1850 5750);
FORCEPROP 0 LAST CDS_SEC 1
J 0
(-1850 5750);
DISPLAY 1.021277 (-1850 5750);
DISPLAY INVISIBLE (-1850 5750);
FORCEPROP 1 LASTPIN (-1900 5675) $PN 1
J 0
(-1895 5637);
DISPLAY 0.489362 (-1895 5637);
PAINT MONO (-1895 5637);
FORCEPROP 1 LASTPIN (-1900 5475) $PN 2
J 0
(-1895 5485);
DISPLAY 0.489362 (-1895 5485);
PAINT MONO (-1895 5485);
FORCEPROP 1 LAST WATTAGE 1/16W
J 0
(-1860 5550);
DISPLAY 0.489362 (-1860 5550);
PAINT SKYBLUE (-1860 5550);
FORCEPROP 1 LAST PACK_TYPE 0402LF
J 0
(-1850 5450);
DISPLAY 0.489362 (-1850 5450);
PAINT SKYBLUE (-1850 5450);
FORCEPROP 1 LAST VALUE 10K
J 0
(-1855 5650);
DISPLAY 0.489362 (-1855 5650);
PAINT SKYBLUE (-1855 5650);
FORCEPROP 1 LAST TOLERANCE 5%
J 0
(-1855 5600);
DISPLAY 0.489362 (-1855 5600);
PAINT SKYBLUE (-1855 5600);
FORCEPROP 1 LAST MATERIAL CHIP
J 0
(-1860 5500);
DISPLAY 0.489362 (-1860 5500);
PAINT SKYBLUE (-1860 5500);
FORCEPROP 1 LAST PART_NUMBER TMP_QCS31002JB28
J 0
(-1860 5450);
DISPLAY 0.489362 (-1860 5450);
PAINT SKYBLUE (-1860 5450);
DISPLAY INVISIBLE (-1860 5450);
FORCEPROP 1 LAST PATH I87
J 0
(-1850 5750);
DISPLAY 0.978723 (-1850 5750);
PAINT WHITE (-1850 5750);
DISPLAY INVISIBLE (-1850 5750);
FORCEPROP 2 LAST CDS_LIB pure_quanta
J 0
(-1900 5575);
DISPLAY INVISIBLE (-1900 5575);
FORCEADD Q_RES..2
(-1900 5925);
FORCEPROP 1 LAST LOCATION R121
J 0
(-1855 6050);
DISPLAY 0.489362 (-1855 6050);
PAINT SKYBLUE (-1855 6050);
FORCEPROP 0 LAST $SEC 1
J 0
(-1850 6100);
DISPLAY 0.680851 (-1850 6100);
PAINT MONO (-1850 6100);
DISPLAY INVISIBLE (-1850 6100);
FORCEPROP 0 LAST CDS_SEC 1
J 0
(-1850 6100);
DISPLAY 1.021277 (-1850 6100);
DISPLAY INVISIBLE (-1850 6100);
FORCEPROP 1 LASTPIN (-1900 6025) $PN 1
J 0
(-1895 5987);
DISPLAY 0.489362 (-1895 5987);
PAINT MONO (-1895 5987);
FORCEPROP 1 LASTPIN (-1900 5825) $PN 2
J 0
(-1895 5835);
DISPLAY 0.489362 (-1895 5835);
PAINT MONO (-1895 5835);
FORCEPROP 1 LAST PACK_TYPE 0402LF
J 0
(-1850 5800);
DISPLAY 0.489362 (-1850 5800);
PAINT SKYBLUE (-1850 5800);
FORCEPROP 1 LAST VALUE 10K
J 0
(-1855 6000);
DISPLAY 0.489362 (-1855 6000);
PAINT SKYBLUE (-1855 6000);
FORCEPROP 1 LAST TOLERANCE 5%
J 0
(-1855 5950);
DISPLAY 0.489362 (-1855 5950);
PAINT SKYBLUE (-1855 5950);
FORCEPROP 1 LAST MATERIAL CHIP
J 0
(-1860 5850);
DISPLAY 0.489362 (-1860 5850);
PAINT SKYBLUE (-1860 5850);
FORCEPROP 1 LAST WATTAGE 1/16W
J 0
(-1860 5900);
DISPLAY 0.489362 (-1860 5900);
PAINT SKYBLUE (-1860 5900);
FORCEPROP 1 LAST PART_NUMBER TMP_QCS31002JB28
J 0
(-1860 5800);
DISPLAY 0.489362 (-1860 5800);
PAINT SKYBLUE (-1860 5800);
DISPLAY INVISIBLE (-1860 5800);
FORCEPROP 1 LAST PATH I88
J 0
(-1850 6100);
DISPLAY 0.978723 (-1850 6100);
PAINT WHITE (-1850 6100);
DISPLAY INVISIBLE (-1850 6100);
FORCEPROP 2 LAST CDS_LIB pure_quanta
J 0
(-1900 5925);
DISPLAY INVISIBLE (-1900 5925);
FORCEADD UNIVERSAL_GND..1
(-2650 4200);
FORCEPROP 3 LASTPIN (-2650 4250) SIG_NAME GND\g
J 0
(-2640 4260);
DISPLAY 0.659574 (-2640 4260);
PAINT MONO (-2640 4260);
DISPLAY INVISIBLE (-2640 4260);
FORCEPROP 1 LAST HDL_POWER GND
J 1
(-2625 4125);
DISPLAY 0.489362 (-2625 4125);
PAINT GREEN (-2625 4125);
FORCEPROP 1 LAST PATH I89
J 0
(-2575 4200);
DISPLAY 0.872340 (-2575 4200);
PAINT AQUA (-2575 4200);
DISPLAY INVISIBLE (-2575 4200);
FORCEPROP 2 LAST CDS_LIB pure_quanta_power
J 0
(-2650 4200);
DISPLAY INVISIBLE (-2650 4200);
FORCEADD UNIVERSAL_GND..1
(-8475 2925);
FORCEPROP 3 LASTPIN (-8475 2975) SIG_NAME GND\g
J 0
(-8465 2985);
DISPLAY 0.659574 (-8465 2985);
PAINT MONO (-8465 2985);
DISPLAY INVISIBLE (-8465 2985);
FORCEPROP 1 LAST HDL_POWER GND
J 1
(-8450 2850);
DISPLAY 0.872340 (-8450 2850);
PAINT GREEN (-8450 2850);
DISPLAY INVISIBLE (-8450 2850);
FORCEPROP 1 LAST PATH I90
J 0
(-8400 2925);
DISPLAY 0.872340 (-8400 2925);
PAINT AQUA (-8400 2925);
DISPLAY INVISIBLE (-8400 2925);
FORCEPROP 2 LAST CDS_LIB pure_quanta_power
J 0
(-8475 2925);
DISPLAY INVISIBLE (-8475 2925);
FORCEADD UNIVERSAL_POWER..1
(-8475 3775);
FORCEPROP 3 LASTPIN (-8475 3725) SIG_NAME P3V3\g
J 0
(-8465 3735);
DISPLAY 0.659574 (-8465 3735);
PAINT MONO (-8465 3735);
DISPLAY INVISIBLE (-8465 3735);
FORCEPROP 1 LAST HDL_POWER P3V3
J 1
(-8475 3825);
DISPLAY 0.489362 (-8475 3825);
PAINT GREEN (-8475 3825);
FORCEPROP 1 LAST PATH I91
J 0
(-8425 3800);
DISPLAY 0.872340 (-8425 3800);
PAINT AQUA (-8425 3800);
DISPLAY INVISIBLE (-8425 3800);
FORCEPROP 2 LAST CDS_LIB pure_quanta_power
J 0
(-8475 3775);
DISPLAY INVISIBLE (-8475 3775);
FORCEADD Q_RES..2
(-8475 3525);
FORCEPROP 1 LAST LOCATION R595
J 0
(-8430 3650);
DISPLAY 0.489362 (-8430 3650);
PAINT SKYBLUE (-8430 3650);
FORCEPROP 0 LAST $SEC 1
J 0
(-8425 3700);
DISPLAY 0.680851 (-8425 3700);
PAINT MONO (-8425 3700);
DISPLAY INVISIBLE (-8425 3700);
FORCEPROP 0 LAST CDS_SEC 1
J 0
(-8425 3700);
DISPLAY 1.021277 (-8425 3700);
DISPLAY INVISIBLE (-8425 3700);
FORCEPROP 1 LASTPIN (-8475 3625) $PN 1
J 0
(-8470 3587);
DISPLAY 0.489362 (-8470 3587);
PAINT MONO (-8470 3587);
FORCEPROP 1 LASTPIN (-8475 3425) $PN 2
J 0
(-8470 3435);
DISPLAY 0.489362 (-8470 3435);
PAINT MONO (-8470 3435);
FORCEPROP 1 LAST PACK_TYPE 0402LF
J 0
(-8435 3400);
DISPLAY 0.489362 (-8435 3400);
PAINT SKYBLUE (-8435 3400);
FORCEPROP 1 LAST VALUE 1K
J 0
(-8430 3600);
DISPLAY 0.489362 (-8430 3600);
PAINT SKYBLUE (-8430 3600);
FORCEPROP 1 LAST TOLERANCE 5%
J 0
(-8430 3550);
DISPLAY 0.489362 (-8430 3550);
PAINT SKYBLUE (-8430 3550);
FORCEPROP 1 LAST MATERIAL EMPTY
J 0
(-8435 3450);
DISPLAY 0.489362 (-8435 3450);
PAINT RED (-8435 3450);
FORCEPROP 1 LAST WATTAGE 1/16W
J 0
(-8435 3500);
DISPLAY 0.489362 (-8435 3500);
PAINT SKYBLUE (-8435 3500);
FORCEPROP 1 LAST PART_NUMBER TMP_QCS21002JB34
J 0
(-8435 3350);
DISPLAY 0.638298 (-8435 3350);
PAINT SKYBLUE (-8435 3350);
DISPLAY INVISIBLE (-8435 3350);
FORCEPROP 1 LAST PATH I92
J 0
(-8425 3700);
DISPLAY 0.978723 (-8425 3700);
PAINT WHITE (-8425 3700);
DISPLAY INVISIBLE (-8425 3700);
FORCEPROP 2 LAST CDS_LIB pure_quanta
J 0
(-8475 3525);
DISPLAY INVISIBLE (-8475 3525);
FORCEADD Q_RES..2
(-8475 3100);
FORCEPROP 1 LAST LOCATION R596
J 0
(-8430 3225);
DISPLAY 0.489362 (-8430 3225);
PAINT SKYBLUE (-8430 3225);
FORCEPROP 0 LAST $SEC 1
J 0
(-8425 3275);
DISPLAY 0.680851 (-8425 3275);
PAINT MONO (-8425 3275);
DISPLAY INVISIBLE (-8425 3275);
FORCEPROP 0 LAST CDS_SEC 1
J 0
(-8425 3275);
DISPLAY 1.021277 (-8425 3275);
DISPLAY INVISIBLE (-8425 3275);
FORCEPROP 1 LASTPIN (-8475 3200) $PN 1
J 0
(-8470 3162);
DISPLAY 0.489362 (-8470 3162);
PAINT MONO (-8470 3162);
FORCEPROP 1 LASTPIN (-8475 3000) $PN 2
J 0
(-8470 3010);
DISPLAY 0.489362 (-8470 3010);
PAINT MONO (-8470 3010);
FORCEPROP 1 LAST PACK_TYPE 0402LF
J 0
(-8435 2975);
DISPLAY 0.489362 (-8435 2975);
PAINT SKYBLUE (-8435 2975);
FORCEPROP 1 LAST VALUE 1K
J 0
(-8430 3175);
DISPLAY 0.489362 (-8430 3175);
PAINT SKYBLUE (-8430 3175);
FORCEPROP 1 LAST TOLERANCE 5%
J 0
(-8430 3125);
DISPLAY 0.489362 (-8430 3125);
PAINT SKYBLUE (-8430 3125);
FORCEPROP 1 LAST MATERIAL CHIP
J 0
(-8435 3025);
DISPLAY 0.489362 (-8435 3025);
PAINT SKYBLUE (-8435 3025);
FORCEPROP 1 LAST WATTAGE 1/16W
J 0
(-8435 3075);
DISPLAY 0.489362 (-8435 3075);
PAINT SKYBLUE (-8435 3075);
FORCEPROP 1 LAST PART_NUMBER TMP_QCS21002JB34
J 0
(-8435 2925);
DISPLAY 0.638298 (-8435 2925);
PAINT SKYBLUE (-8435 2925);
DISPLAY INVISIBLE (-8435 2925);
FORCEPROP 1 LAST PATH I93
J 0
(-8425 3275);
DISPLAY 0.978723 (-8425 3275);
PAINT WHITE (-8425 3275);
DISPLAY INVISIBLE (-8425 3275);
FORCEPROP 2 LAST CDS_LIB pure_quanta
J 0
(-8475 3100);
DISPLAY INVISIBLE (-8475 3100);
FORCEADD OFFPAGE..1
(-4850 5025);
FORCEPROP 2 LAST $XR0 111 
J 0
(-5102 5025);
DISPLAY 0.638298 (-5102 5025);
PAINT MONO (-5102 5025);
FORCEPROP 2 LAST PATH I94
J 0
(-4800 5100);
DISPLAY 1.021277 (-4800 5100);
DISPLAY INVISIBLE (-4800 5100);
FORCEPROP 1 LAST COMMENT_BODY TRUE
J 0
(-4725 4925);
DISPLAY 0.872340 (-4725 4925);
PAINT GREEN (-4725 4925);
DISPLAY INVISIBLE (-4725 4925);
FORCEPROP 1 LAST OFFPAGE TRUE
J 0
(-4525 4900);
DISPLAY 0.872340 (-4525 4900);
PAINT GREEN (-4525 4900);
DISPLAY INVISIBLE (-4525 4900);
FORCEPROP 2 LAST CDS_LIB standard
J 0
(-4850 5025);
DISPLAY INVISIBLE (-4850 5025);
FORCEADD OFFPAGE..1
(-5650 4875);
FORCEPROP 2 LAST $XR1 112 
J 0
(-6052 4875);
DISPLAY 0.638298 (-6052 4875);
PAINT MONO (-6052 4875);
FORCEPROP 2 LAST $XR0 111 
J 0
(-5932 4875);
DISPLAY 0.638298 (-5932 4875);
PAINT MONO (-5932 4875);
FORCEPROP 2 LAST PATH I95
J 0
(-5600 4950);
DISPLAY 1.021277 (-5600 4950);
DISPLAY INVISIBLE (-5600 4950);
FORCEPROP 1 LAST COMMENT_BODY TRUE
J 0
(-5525 4775);
DISPLAY 0.872340 (-5525 4775);
PAINT GREEN (-5525 4775);
DISPLAY INVISIBLE (-5525 4775);
FORCEPROP 1 LAST OFFPAGE TRUE
J 0
(-5325 4750);
DISPLAY 0.872340 (-5325 4750);
PAINT GREEN (-5325 4750);
DISPLAY INVISIBLE (-5325 4750);
FORCEPROP 2 LAST CDS_LIB standard
J 0
(-5650 4875);
DISPLAY INVISIBLE (-5650 4875);
FORCEADD OFFPAGE..3
R 2
(-5650 4925);
FORCEPROP 2 LAST $XR1 112 
J 0
(-6050 4925);
DISPLAY 0.638298 (-6050 4925);
PAINT MONO (-6050 4925);
FORCEPROP 2 LAST $XR0 111 
J 0
(-5930 4925);
DISPLAY 0.638298 (-5930 4925);
PAINT MONO (-5930 4925);
FORCEPROP 2 LAST PATH I96
J 0
(-5600 5000);
DISPLAY 1.021277 (-5600 5000);
DISPLAY INVISIBLE (-5600 5000);
FORCEPROP 1 LAST COMMENT_BODY TRUE
J 2
(-5600 4825);
DISPLAY 0.872340 (-5600 4825);
PAINT PEACH (-5600 4825);
DISPLAY INVISIBLE (-5600 4825);
FORCEPROP 1 LAST OFFPAGE TRUE
J 2
(-5975 4800);
DISPLAY 0.872340 (-5975 4800);
PAINT GREEN (-5975 4800);
DISPLAY INVISIBLE (-5975 4800);
FORCEPROP 2 LAST CDS_LIB standard
J 0
(-5650 4925);
DISPLAY INVISIBLE (-5650 4925);
FORCEADD Q_RES..1
(-4850 4875);
FORCEPROP 1 LAST LOCATION R626
J 0
(-5025 4875);
DISPLAY 0.489362 (-5025 4875);
PAINT SKYBLUE (-5025 4875);
FORCEPROP 0 LAST $SEC 1
J 0
(-4975 4925);
DISPLAY 0.680851 (-4975 4925);
PAINT MONO (-4975 4925);
DISPLAY INVISIBLE (-4975 4925);
FORCEPROP 0 LAST CDS_SEC 1
J 0
(-4975 4925);
DISPLAY 1.021277 (-4975 4925);
DISPLAY INVISIBLE (-4975 4925);
FORCEPROP 1 LASTPIN (-4950 4875) $PN 1
J 0
(-4938 4887);
DISPLAY 0.489362 (-4938 4887);
PAINT MONO (-4938 4887);
FORCEPROP 1 LASTPIN (-4750 4875) $PN 2
J 0
(-4788 4887);
DISPLAY 0.489362 (-4788 4887);
PAINT MONO (-4788 4887);
FORCEPROP 1 LAST VALUE 0
J 2
(-4725 4875);
DISPLAY 0.489362 (-4725 4875);
PAINT SKYBLUE (-4725 4875);
FORCEPROP 1 LAST PACK_TYPE 0402LF
J 0
(-4800 4800);
DISPLAY 0.489362 (-4800 4800);
PAINT SKYBLUE (-4800 4800);
DISPLAY INVISIBLE (-4800 4800);
FORCEPROP 1 LAST PART_NUMBER CS00002JB38
J 0
(-4825 4925);
DISPLAY 0.489362 (-4825 4925);
PAINT SKYBLUE (-4825 4925);
DISPLAY INVISIBLE (-4825 4925);
FORCEPROP 1 LAST TOLERANCE 5%
J 0
(-4875 4800);
DISPLAY 0.489362 (-4875 4800);
PAINT SKYBLUE (-4875 4800);
DISPLAY INVISIBLE (-4875 4800);
FORCEPROP 1 LAST MATERIAL CHIP
J 0
(-4425 4800);
DISPLAY 0.489362 (-4425 4800);
PAINT SKYBLUE (-4425 4800);
DISPLAY INVISIBLE (-4425 4800);
FORCEPROP 1 LAST WATTAGE 1/16W
J 2
(-4450 4800);
DISPLAY 0.489362 (-4450 4800);
PAINT SKYBLUE (-4450 4800);
DISPLAY INVISIBLE (-4450 4800);
FORCEPROP 1 LAST PATH I97
J 0
(-4900 5025);
DISPLAY 0.978723 (-4900 5025);
PAINT WHITE (-4900 5025);
DISPLAY INVISIBLE (-4900 5025);
FORCEPROP 2 LAST CDS_LIB pure_quanta
J 0
(-4850 4875);
DISPLAY INVISIBLE (-4850 4875);
FORCEADD Q_RES..1
(-4850 4925);
FORCEPROP 1 LAST LOCATION R625
J 0
(-5025 4925);
DISPLAY 0.489362 (-5025 4925);
PAINT SKYBLUE (-5025 4925);
FORCEPROP 0 LAST $SEC 1
J 0
(-4975 4975);
DISPLAY 0.680851 (-4975 4975);
PAINT MONO (-4975 4975);
DISPLAY INVISIBLE (-4975 4975);
FORCEPROP 0 LAST CDS_SEC 1
J 0
(-4975 4975);
DISPLAY 1.021277 (-4975 4975);
DISPLAY INVISIBLE (-4975 4975);
FORCEPROP 1 LASTPIN (-4950 4925) $PN 1
J 0
(-4938 4937);
DISPLAY 0.489362 (-4938 4937);
PAINT MONO (-4938 4937);
FORCEPROP 1 LASTPIN (-4750 4925) $PN 2
J 0
(-4788 4937);
DISPLAY 0.489362 (-4788 4937);
PAINT MONO (-4788 4937);
FORCEPROP 1 LAST VALUE 0
J 2
(-4725 4925);
DISPLAY 0.489362 (-4725 4925);
PAINT SKYBLUE (-4725 4925);
FORCEPROP 1 LAST PACK_TYPE 0402LF
J 0
(-4800 4850);
DISPLAY 0.489362 (-4800 4850);
PAINT SKYBLUE (-4800 4850);
DISPLAY INVISIBLE (-4800 4850);
FORCEPROP 1 LAST PART_NUMBER CS00002JB38
J 0
(-4825 4975);
DISPLAY 0.489362 (-4825 4975);
PAINT SKYBLUE (-4825 4975);
DISPLAY INVISIBLE (-4825 4975);
FORCEPROP 1 LAST TOLERANCE 5%
J 0
(-4875 4850);
DISPLAY 0.489362 (-4875 4850);
PAINT SKYBLUE (-4875 4850);
DISPLAY INVISIBLE (-4875 4850);
FORCEPROP 1 LAST MATERIAL CHIP
J 0
(-4425 4850);
DISPLAY 0.489362 (-4425 4850);
PAINT SKYBLUE (-4425 4850);
DISPLAY INVISIBLE (-4425 4850);
FORCEPROP 1 LAST WATTAGE 1/16W
J 2
(-4450 4850);
DISPLAY 0.489362 (-4450 4850);
PAINT SKYBLUE (-4450 4850);
DISPLAY INVISIBLE (-4450 4850);
FORCEPROP 1 LAST PATH I98
J 0
(-4900 5075);
DISPLAY 0.978723 (-4900 5075);
PAINT WHITE (-4900 5075);
DISPLAY INVISIBLE (-4900 5075);
FORCEPROP 2 LAST CDS_LIB pure_quanta
J 0
(-4850 4925);
DISPLAY INVISIBLE (-4850 4925);
FORCEADD OFFPAGE..2
(-7625 3325);
FORCEPROP 2 LAST $XR0 111 
J 0
(-7436 3325);
DISPLAY 0.638298 (-7436 3325);
PAINT MONO (-7436 3325);
FORCEPROP 2 LAST PATH I99
J 0
(-7450 3400);
DISPLAY 1.021277 (-7450 3400);
DISPLAY INVISIBLE (-7450 3400);
FORCEPROP 1 LAST COMMENT_BODY TRUE
J 0
(-7670 3230);
DISPLAY 0.872340 (-7670 3230);
PAINT GREEN (-7670 3230);
DISPLAY INVISIBLE (-7670 3230);
FORCEPROP 1 LAST OFFPAGE TRUE
J 0
(-7300 3200);
DISPLAY 0.723404 (-7300 3200);
PAINT GREEN (-7300 3200);
DISPLAY INVISIBLE (-7300 3200);
FORCEPROP 2 LAST CDS_LIB standard
J 0
(-7625 3325);
DISPLAY INVISIBLE (-7625 3325);
FORCEADD DESIGN_NOTE..1
(-3425 3900);
FORCEPROP 0 LAST L1 ADDRESS : 6C/D8
J 0
(-3625 3775);
DISPLAY 1.276596 (-3625 3775);
FORCEPROP 1 LAST COMMENT_BODY TRUE
J 0
(-3400 4000);
DISPLAY 0.978723 (-3400 4000);
DISPLAY INVISIBLE (-3400 4000);
FORCEPROP 2 LAST CDS_LIB pure_quanta_power
J 0
(-3425 3900);
DISPLAY INVISIBLE (-3425 3900);
FORCEADD DNS..2
(-1600 4500);
PAINT RED (-1600 4500);
FORCEPROP 1 LAST COMMENT_BODY TRUE
J 0
(-1600 4500);
DISPLAY INVISIBLE (-1600 4500);
FORCEPROP 2 LAST CDS_LIB mstr_misc
J 0
(-1600 4500);
DISPLAY INVISIBLE (-1600 4500);
FORCEADD QUANTA_TITLE_BLOCK_C..1
(-100 100);
FORCEPROP 0 LAST CDS_CON_LAST_MODIFIED Fri Mar 11 14:53:11 2022
J 0
(-1985 115);
DISPLAY INVISIBLE (-1985 115);
FORCEPROP 1 LAST CUSTOM_TXT_CDS <CON_LAST_MODIFIED>
J 0
(-1985 115);
DISPLAY 0.978723 (-1985 115);
FORCEPROP 2 LAST CUSTOM_TXT_CDS <XR_PAGE_TITLE>
J 0
(-7990 5350);
DISPLAY 0.638298 (-7990 5350);
PAINT PINK (-7990 5350);
DISPLAY INVISIBLE (-7990 5350);
FORCEPROP 1 LAST CUSTOM_TXT_CDS <NAME_2>
J 0
(-3275 150);
FORCEPROP 1 LAST CUSTOM_TXT_CDS <NAME_1>
J 0
(-3275 275);
FORCEPROP 1 LAST CUSTOM_TXT_CDS <Q_NUMBER>
J 0
(-1503 203);
DISPLAY 1.212766 (-1503 203);
FORCEPROP 1 LAST CUSTOM_TXT_CDS <Q_PROJ>
J 0
(-2482 202);
DISPLAY 1.212766 (-2482 202);
FORCEPROP 1 LAST CUSTOM_TXT_CDS <Q_REV>
J 0
(-284 203);
DISPLAY 1.212766 (-284 203);
FORCEPROP 1 LAST CUSTOM_TXT_CDS <CON_PAGE_NUM> OF <CON_TOTAL_PAGES>
J 0
(-546 118);
DISPLAY 0.978723 (-546 118);
FORCEPROP 1 LAST Q_TITLE CLK BUF - PCIEX16/OCP NIC
J 0
(-9400 150);
DISPLAY 2.446809 (-9400 150);
PAINT GREEN (-9400 150);
FORCEPROP 1 LAST Q_DEPT BU9
J 1
(-3863 149);
DISPLAY 1.957447 (-3863 149);
PAINT GREEN (-3863 149);
FORCEPROP 1 LAST COMMENT_BODY TRUE
J 0
(-88 87);
DISPLAY 0.978723 (-88 87);
PAINT GREEN (-88 87);
DISPLAY INVISIBLE (-88 87);
FORCEPROP 1 LAST CDS_LMAN_SYM_OUTLINE -9475,6775,100,-125
J 0
(-100 100);
DISPLAY 0.468085 (-100 100);
PAINT GREEN (-100 100);
DISPLAY INVISIBLE (-100 100);
FORCEPROP 2 LAST CDS_LIB pure_quanta
J 0
(-100 100);
DISPLAY INVISIBLE (-100 100);
FORCEPROP 2 LAST PAGE_BORDER TRUE
J 0
(-7990 5350);
DISPLAY 0.638298 (-7990 5350);
PAINT PINK (-7990 5350);
DISPLAY INVISIBLE (-7990 5350);
FORCEPROP 2 LAST CDS_XR_PAGE_TITLE CR-111 : @T6G_MB_LIB.T6G(SCH_1):PAGE111
J 0
(-7990 5350);
DISPLAY 0.638298 (-7990 5350);
PAINT PINK (-7990 5350);
DISPLAY INVISIBLE (-7990 5350);
FORCEADD DNS..2
(-8475 3550);
PAINT RED (-8475 3550);
FORCEPROP 1 LAST COMMENT_BODY TRUE
J 0
(-8475 3550);
DISPLAY INVISIBLE (-8475 3550);
FORCEPROP 2 LAST CDS_LIB mstr_misc
J 0
(-8475 3550);
DISPLAY INVISIBLE (-8475 3550);
FORCEADD DNS..2
(-6875 3225);
PAINT RED (-6875 3225);
FORCEPROP 1 LAST COMMENT_BODY TRUE
J 0
(-6875 3225);
DISPLAY INVISIBLE (-6875 3225);
FORCEPROP 2 LAST CDS_LIB mstr_misc
J 0
(-6875 3225);
DISPLAY INVISIBLE (-6875 3225);
FORCEADD DNS..2
(-1575 4375);
PAINT RED (-1575 4375);
FORCEPROP 1 LAST COMMENT_BODY TRUE
J 0
(-1575 4375);
DISPLAY INVISIBLE (-1575 4375);
FORCEPROP 2 LAST CDS_LIB mstr_misc
J 0
(-1575 4375);
DISPLAY INVISIBLE (-1575 4375);
FORCEADD DNS..2
(-6850 3600);
PAINT RED (-6850 3600);
FORCEPROP 1 LAST COMMENT_BODY TRUE
J 0
(-6850 3600);
DISPLAY INVISIBLE (-6850 3600);
FORCEPROP 2 LAST CDS_LIB mstr_misc
J 0
(-6850 3600);
DISPLAY INVISIBLE (-6850 3600);
WIRE 16 -1 (-1675 1425)(-1675 1475);
WIRE 16 -1 (-1775 975)(-1775 825);
WIRE 16 -1 (-1975 975)(-1775 975);
WIRE 16 -1 (-3000 1425)(-3000 1475);
WIRE 16 -1 (-6850 3750)(-6850 3675);
WIRE 16 -1 (-6850 3000)(-6850 3075);
WIRE 16 -1 (-3100 2200)(-3100 2050);
WIRE 16 -1 (-3100 2975)(-3100 3025);
WIRE 16 -1 (-6250 5225)(-6250 5100);
WIRE 16 -1 (-6450 5225)(-6450 5100);
WIRE 16 -1 (-6700 5225)(-6700 5100);
WIRE 16 -1 (-7365 4690)(-7365 4565);
WIRE 16 -1 (-7595 4695)(-7595 4570);
WIRE 16 -1 (-7825 4700)(-7825 4575);
WIRE 16 -1 (-8050 4700)(-8050 4575);
WIRE 16 -1 (-8300 4700)(-8300 4575);
WIRE 16 -1 (-8700 4735)(-8700 4600);
WIRE 16 -1 (-1900 6075)(-1900 6025);
WIRE 16 -1 (-2650 4375)(-2750 4375);
WIRE 16 -1 (-2650 4375)(-2650 4250);
WIRE 16 -1 (-8475 3000)(-8475 2975);
WIRE 16 -1 (-8475 3625)(-8475 3725);
WIRE 16 -1 (-2300 2675)(-1950 2675);
FORCEPROP 2 LAST SIG_NAME PWRGD_PVDD11_S3_P0_R_N
J 0
(-2385 2685);
DISPLAY 0.446809 (-2385 2685);
WIRE 16 -1 (-1975 1325)(-1800 1325);
WIRE 16 -1 (-1800 1325)(-1800 1725);
WIRE 16 -1 (-1675 1725)(-1800 1725);
WIRE 16 -1 (-1800 1725)(-1800 1775);
WIRE 16 -1 (-1675 1675)(-1675 1725);
WIRE 16 -1 (-1750 2150)(-1625 2150);
WIRE 16 -1 (-1750 2150)(-1750 2200);
WIRE 16 -1 (-1750 2200)(-1625 2200);
WIRE 16 -1 (-1750 2200)(-1750 2250);
WIRE 16 -1 (-1750 2250)(-1750 2300);
WIRE 16 -1 (-1750 2250)(-1625 2250);
WIRE 16 -1 (-1750 2300)(-1750 2500);
WIRE 16 -1 (-1750 2300)(-1625 2300);
WIRE 16 -1 (-1225 4475)(-1225 4375);
WIRE 16 -1 (-1575 4475)(-1225 4475);
WIRE 16 -1 (-1225 4250)(-1225 4375);
WIRE 16 -1 (-1225 4375)(-1575 4375);
WIRE 16 -1 (-1775 2750)(-1675 2750);
WIRE 16 -1 (-1775 2750)(-1775 2800);
WIRE 16 -1 (-1775 2800)(-1775 2850);
WIRE 16 -1 (-1775 2800)(-1675 2800);
WIRE 16 -1 (-1775 2850)(-1775 2900);
WIRE 16 -1 (-1775 2850)(-1675 2850);
WIRE 16 -1 (-1775 2900)(-1775 3100);
WIRE 16 -1 (-1775 2900)(-1675 2900);
WIRE 16 -1 (-2875 1325)(-2875 1725);
WIRE 16 -1 (-2875 1325)(-2725 1325);
WIRE 16 -1 (-2875 1725)(-2875 1750);
WIRE 16 -1 (-3000 1725)(-2875 1725);
WIRE 16 -1 (-3000 1675)(-3000 1725);
WIRE 16 -1 (-4625 5525)(-4625 5325);
WIRE 16 -1 (-4000 5325)(-4625 5325);
WIRE 16 -1 (-4000 5425)(-4225 5425);
WIRE 16 -1 (-4225 5425)(-4225 5475);
WIRE 16 -1 (-4000 5475)(-4225 5475);
WIRE 16 -1 (-4225 5475)(-4225 5525);
WIRE 16 -1 (-4000 5525)(-4225 5525);
WIRE 16 -1 (-4225 5525)(-4225 5575);
WIRE 16 -1 (-4225 5575)(-4225 5625);
WIRE 16 -1 (-4000 5575)(-4225 5575);
WIRE 16 -1 (-4000 5625)(-4225 5625);
WIRE 16 -1 (-4225 5625)(-4225 5900);
WIRE 16 -1 (-2625 5900)(-2625 5625);
WIRE 16 -1 (-2750 5625)(-2625 5625);
WIRE 16 -1 (-6250 5475)(-6250 5625);
WIRE 16 -1 (-6250 5425)(-6250 5475);
WIRE 16 -1 (-6450 5475)(-6250 5475);
WIRE 16 -1 (-6450 5425)(-6450 5475);
WIRE 16 -1 (-6700 5475)(-6450 5475);
WIRE 16 -1 (-7100 5475)(-6700 5475);
WIRE 16 -1 (-6700 5425)(-6700 5475);
WIRE 16 -1 (-7365 4975)(-7365 4890);
WIRE 16 -1 (-7365 4980)(-7365 4975);
WIRE 16 -1 (-7595 4975)(-7365 4975);
WIRE 16 -1 (-7595 4895)(-7595 4975);
WIRE 16 -1 (-7825 4975)(-7595 4975);
WIRE 16 -1 (-7825 4975)(-7825 4900);
WIRE 16 -1 (-8050 4975)(-7825 4975);
WIRE 16 -1 (-8050 4900)(-8050 4975);
WIRE 16 -1 (-8300 4975)(-8050 4975);
WIRE 16 -1 (-8300 4900)(-8300 4975);
WIRE 16 -1 (-8300 4975)(-8700 4975);
WIRE 16 -1 (-8700 5475)(-8700 4975);
WIRE 16 -1 (-8700 4975)(-8700 4935);
WIRE 16 -1 (-7550 5475)(-8700 5475);
WIRE 16 -1 (-8700 5475)(-8775 5475);
WIRE 16 -1 (-7550 5475)(-7300 5475);
WIRE 16 -1 (-7550 5625)(-7550 5475);
WIRE 16 -1 (-9225 5575)(-9225 5475);
WIRE 16 -1 (-9225 5475)(-8975 5475);
WIRE 16 -1 (-2725 1225)(-3625 1225);
FORCEPROP 2 LAST SIG_NAME SMB_CPU0_2_SCL
J 0
(-3475 1235);
DISPLAY 0.489362 (-3475 1235);
WIRE 16 -1 (-2725 1175)(-3625 1175);
FORCEPROP 2 LAST SIG_NAME SMB_CPU0_2_SDA
J 0
(-3475 1185);
DISPLAY 0.489362 (-3475 1185);
WIRE 16 -1 (-2725 1125)(-3625 1125);
FORCEPROP 2 LAST SIG_NAME SMB_CPU0_3_SCL
J 0
(-3475 1135);
DISPLAY 0.489362 (-3475 1135);
WIRE 16 -1 (-2725 1075)(-3625 1075);
FORCEPROP 2 LAST SIG_NAME SMB_CPU0_3_SDA
J 0
(-3475 1085);
DISPLAY 0.489362 (-3475 1085);
WIRE 16 -1 (-1425 2200)(-750 2200);
FORCEPROP 2 LAST SIG_NAME SMB_CPU0_3_XLTR_SCL
J 0
(-1275 2210);
DISPLAY 0.489362 (-1275 2210);
WIRE 16 -1 (-3350 975)(-2725 975);
FORCEPROP 2 LAST SIG_NAME PWRGD_PVDD11_S3_P0_R_N
J 2
(-2835 985);
DISPLAY 0.489362 (-2835 985);
WIRE 16 -1 (-3100 2500)(-3100 2675);
WIRE 16 -1 (-2500 2675)(-3100 2675);
FORCEPROP 2 LAST SIG_NAME PWRGD_PVDD11_S3_P0_N
J 2
(-2635 2685);
DISPLAY 0.489362 (-2635 2685);
FORCEPROP 2 LASTPROP $XRERR UNIQUE?
J 0
(-2875 2685);
DISPLAY 0.638298 (-2875 2685);
PAINT MONO (-2875 2685);
DISPLAY INVISIBLE (-2875 2685);
WIRE 16 -1 (-3100 2775)(-3100 2675);
WIRE 16 -1 (-3300 2300)(-3900 2300);
FORCEPROP 2 LAST SIG_NAME PWRGD_PVDD11_S3_P0
J 2
(-3485 2310);
DISPLAY 0.489362 (-3485 2310);
WIRE 16 -1 (-4000 4775)(-4750 4775);
FORCEPROP 2 LAST SIG_NAME FM_CLK_BUFFER2_EN_R
J 0
(-4660 4785);
DISPLAY 0.489362 (-4660 4785);
FORCEPROP 2 LASTPROP $XRERR UNIQUE?
J 0
(-4900 4785);
DISPLAY 0.638298 (-4900 4785);
PAINT MONO (-4900 4785);
DISPLAY INVISIBLE (-4900 4785);
WIRE 16 -1 (-4800 5175)(-4000 5175);
FORCEPROP 2 LAST SIG_NAME CLK_100M_CPU1_CLK15_DP
J 0
(-4635 5185);
DISPLAY 0.489362 (-4635 5185);
WIRE 16 -1 (-1600 5175)(-850 5175);
FORCEPROP 2 LAST SIG_NAME CLK_100M_OCP_DP
J 0
(-1510 5185);
DISPLAY 0.489362 (-1510 5185);
WIRE 16 -1 (-1600 5125)(-850 5125);
FORCEPROP 2 LAST SIG_NAME CLK_100M_OCP_DN
J 0
(-1510 5135);
DISPLAY 0.489362 (-1510 5135);
WIRE 16 -1 (-2750 5275)(-1800 5275);
FORCEPROP 2 LAST SIG_NAME CLK_100M_SLOT3_R_DP
J 0
(-2660 5285);
DISPLAY 0.489362 (-2660 5285);
FORCEPROP 2 LASTPROP $XRERR UNIQUE?
J 0
(-2900 5285);
DISPLAY 0.638298 (-2900 5285);
PAINT MONO (-2900 5285);
DISPLAY INVISIBLE (-2900 5285);
WIRE 16 -1 (-1925 4725)(-1925 4475);
WIRE 16 -1 (-1800 4725)(-1925 4725);
WIRE 16 -1 (-1925 4725)(-2750 4725);
FORCEPROP 2 LAST SIG_NAME FM_CLK_100M_SLOT3_OE_N_R
J 0
(-2660 4735);
DISPLAY 0.489362 (-2660 4735);
FORCEPROP 2 LASTPROP $XRERR UNIQUE?
J 0
(-2900 4735);
DISPLAY 0.638298 (-2900 4735);
PAINT MONO (-2900 4735);
DISPLAY INVISIBLE (-2900 4735);
WIRE 16 -1 (-1925 4475)(-1775 4475);
WIRE 16 -1 (-1975 1125)(-1075 1125);
FORCEPROP 2 LAST SIG_NAME SMB_CPU0_3_XLTR_SCL
J 0
(-1825 1135);
DISPLAY 0.489362 (-1825 1135);
WIRE 16 -1 (-1425 2150)(-750 2150);
FORCEPROP 2 LAST SIG_NAME SMB_CPU0_3_XLTR_SDA
J 0
(-1275 2160);
DISPLAY 0.489362 (-1275 2160);
WIRE 16 -1 (-1425 2300)(-750 2300);
FORCEPROP 2 LAST SIG_NAME SMB_CPU0_2_XLTR_SCL
J 0
(-1275 2310);
DISPLAY 0.489362 (-1275 2310);
WIRE 16 -1 (-8475 3200)(-8475 3325);
WIRE 16 -1 (-7675 3325)(-8475 3325);
FORCEPROP 2 LAST SIG_NAME SADR_2
J 0
(-8310 3335);
DISPLAY 0.489362 (-8310 3335);
WIRE 16 -1 (-8475 3325)(-8475 3425);
WIRE 16 -1 (-6850 3325)(-5950 3325);
FORCEPROP 2 LAST SIG_NAME FM_CLK_BUFFER2_EN
J 0
(-6585 3335);
DISPLAY 0.489362 (-6585 3335);
WIRE 16 -1 (-6850 3475)(-6850 3325);
WIRE 16 -1 (-6850 3325)(-6850 3275);
WIRE 16 -1 (-5600 4775)(-4950 4775);
FORCEPROP 2 LAST SIG_NAME FM_CLK_BUFFER2_EN
J 0
(-5585 4785);
DISPLAY 0.489362 (-5585 4785);
WIRE 16 -1 (-5600 4875)(-4950 4875);
FORCEPROP 2 LAST SIG_NAME SMB_CPU0_3_XLTR_SCL
J 0
(-5585 4885);
DISPLAY 0.489362 (-5585 4885);
WIRE 16 -1 (-5600 4925)(-4950 4925);
FORCEPROP 2 LAST SIG_NAME SMB_CPU0_3_XLTR_SDA
J 0
(-5585 4935);
DISPLAY 0.489362 (-5585 4935);
WIRE 16 -1 (-4000 4875)(-4750 4875);
FORCEPROP 2 LAST SIG_NAME SMB_CLK_BUF2_SCL
J 0
(-4660 4885);
DISPLAY 0.489362 (-4660 4885);
FORCEPROP 2 LASTPROP $XRERR UNIQUE?
J 0
(-4900 4885);
DISPLAY 0.638298 (-4900 4885);
PAINT MONO (-4900 4885);
DISPLAY INVISIBLE (-4900 4885);
WIRE 16 -1 (-4000 4925)(-4750 4925);
FORCEPROP 2 LAST SIG_NAME SMB_CLK_BUF2_SDA
J 0
(-4660 4935);
DISPLAY 0.489362 (-4660 4935);
FORCEPROP 2 LASTPROP $XRERR UNIQUE?
J 0
(-4900 4935);
DISPLAY 0.638298 (-4900 4935);
PAINT MONO (-4900 4935);
DISPLAY INVISIBLE (-4900 4935);
WIRE 16 -1 (-4800 5125)(-4000 5125);
FORCEPROP 2 LAST SIG_NAME CLK_100M_CPU1_CLK15_DN
J 0
(-4635 5135);
DISPLAY 0.489362 (-4635 5135);
WIRE 16 -1 (-4000 5025)(-4800 5025);
FORCEPROP 2 LAST SIG_NAME SADR_2
J 0
(-4635 5035);
DISPLAY 0.489362 (-4635 5035);
WIRE 16 -1 (-1975 1225)(-1075 1225);
FORCEPROP 2 LAST SIG_NAME SMB_CPU0_2_XLTR_SCL
J 0
(-1825 1235);
DISPLAY 0.489362 (-1825 1235);
WIRE 16 -1 (-1975 1175)(-1075 1175);
FORCEPROP 2 LAST SIG_NAME SMB_CPU0_2_XLTR_SDA
J 0
(-1825 1185);
DISPLAY 0.489362 (-1825 1185);
WIRE 16 -1 (-1975 1075)(-1075 1075);
FORCEPROP 2 LAST SIG_NAME SMB_CPU0_3_XLTR_SDA
J 0
(-1825 1085);
DISPLAY 0.489362 (-1825 1085);
WIRE 16 -1 (-1425 2250)(-750 2250);
FORCEPROP 2 LAST SIG_NAME SMB_CPU0_2_XLTR_SDA
J 0
(-1275 2260);
DISPLAY 0.489362 (-1275 2260);
WIRE 16 -1 (-875 2850)(-1475 2850);
FORCEPROP 2 LAST SIG_NAME SMB_CPU0_2_SDA
J 0
(-1325 2860);
DISPLAY 0.489362 (-1325 2860);
WIRE 16 -1 (-875 2800)(-1475 2800);
FORCEPROP 2 LAST SIG_NAME SMB_CPU0_3_SCL
J 0
(-1325 2810);
DISPLAY 0.489362 (-1325 2810);
WIRE 16 -1 (-875 2900)(-1475 2900);
FORCEPROP 2 LAST SIG_NAME SMB_CPU0_2_SCL
J 0
(-1325 2910);
DISPLAY 0.489362 (-1325 2910);
WIRE 16 -1 (-875 2750)(-1475 2750);
FORCEPROP 2 LAST SIG_NAME SMB_CPU0_3_SDA
J 0
(-1325 2760);
DISPLAY 0.489362 (-1325 2760);
WIRE 16 -1 (-2750 5475)(-2450 5475);
WIRE 16 -1 (-2450 5750)(-2450 5475);
FORCEPROP 2 LAST SIG_NAME CLKBUF2_PLL_MODE
J 0
(-2485 5760);
DISPLAY 0.489362 (-2485 5760);
FORCEPROP 2 LASTPROP $XRERR UNIQUE?
J 0
(-2725 5760);
DISPLAY 0.638298 (-2725 5760);
PAINT MONO (-2725 5760);
DISPLAY INVISIBLE (-2725 5760);
WIRE 16 -1 (-2450 5750)(-1900 5750);
WIRE 16 -1 (-1900 5825)(-1900 5750);
WIRE 16 -1 (-1900 5750)(-1900 5675);
WIRE 16 -1 (-2750 5225)(-1800 5225);
FORCEPROP 2 LAST SIG_NAME CLK_100M_SLOT3_R_DN
J 0
(-2660 5235);
DISPLAY 0.489362 (-2660 5235);
FORCEPROP 2 LASTPROP $XRERR UNIQUE?
J 0
(-2900 5235);
DISPLAY 0.638298 (-2900 5235);
PAINT MONO (-2900 5235);
DISPLAY INVISIBLE (-2900 5235);
WIRE 16 -1 (-2750 5125)(-1800 5125);
FORCEPROP 2 LAST SIG_NAME CLK_100M_OCP_R_DN
J 0
(-2660 5135);
DISPLAY 0.489362 (-2660 5135);
FORCEPROP 2 LASTPROP $XRERR UNIQUE?
J 0
(-2900 5135);
DISPLAY 0.638298 (-2900 5135);
PAINT MONO (-2900 5135);
DISPLAY INVISIBLE (-2900 5135);
WIRE 16 -1 (-2750 5175)(-1800 5175);
FORCEPROP 2 LAST SIG_NAME CLK_100M_OCP_R_DP
J 0
(-2660 5185);
DISPLAY 0.489362 (-2660 5185);
FORCEPROP 2 LASTPROP $XRERR UNIQUE?
J 0
(-2900 5185);
DISPLAY 0.638298 (-2900 5185);
PAINT MONO (-2900 5185);
DISPLAY INVISIBLE (-2900 5185);
WIRE 16 -1 (-1975 4675)(-1975 4375);
WIRE 16 -1 (-2750 4675)(-1975 4675);
FORCEPROP 2 LAST SIG_NAME FM_CLK_100M_OCP_OE_N_R
J 0
(-2660 4685);
DISPLAY 0.489362 (-2660 4685);
FORCEPROP 2 LASTPROP $XRERR UNIQUE?
J 0
(-2900 4685);
DISPLAY 0.638298 (-2900 4685);
PAINT MONO (-2900 4685);
DISPLAY INVISIBLE (-2900 4685);
WIRE 16 -1 (-1975 4675)(-1800 4675);
WIRE 16 -1 (-1975 4375)(-1775 4375);
WIRE 16 -1 (-1600 4725)(-850 4725);
FORCEPROP 2 LAST SIG_NAME FM_CLK_100M_SLOT3_OE_N
J 0
(-1510 4735);
DISPLAY 0.489362 (-1510 4735);
WIRE 16 -1 (-1600 4675)(-850 4675);
FORCEPROP 2 LAST SIG_NAME FM_CLK_100M_OCP_OE_N
J 0
(-1510 4685);
DISPLAY 0.489362 (-1510 4685);
WIRE 16 -1 (-1600 5275)(-850 5275);
FORCEPROP 2 LAST SIG_NAME CLK_100M_SLOT3_DP
J 0
(-1510 5285);
DISPLAY 0.489362 (-1510 5285);
WIRE 16 -1 (-1600 5225)(-850 5225);
FORCEPROP 2 LAST SIG_NAME CLK_100M_SLOT3_DN
J 0
(-1510 5235);
DISPLAY 0.489362 (-1510 5235);
DOT 1 (-1900 5750);
DOT 1 (-7365 4975);
DOT 1 (-1225 4375);
DOT 1 (-4225 5575);
DOT 1 (-4225 5525);
DOT 1 (-4225 5475);
DOT 1 (-8475 3325);
DOT 1 (-4225 5625);
DOT 1 (-6250 5475);
DOT 1 (-6450 5475);
DOT 1 (-6700 5475);
DOT 1 (-7550 5475);
DOT 1 (-7595 4975);
DOT 1 (-7825 4975);
DOT 1 (-8050 4975);
DOT 1 (-8300 4975);
DOT 1 (-8700 4975);
DOT 1 (-1800 1725);
DOT 1 (-6850 3325);
DOT 1 (-1975 4675);
DOT 1 (-1775 2850);
DOT 1 (-1775 2800);
DOT 1 (-1750 2200);
DOT 1 (-1925 4725);
DOT 1 (-2875 1725);
DOT 1 (-8700 5475);
DOT 1 (-1775 2900);
DOT 1 (-1750 2300);
DOT 1 (-1750 2250);
DOT 1 (-3100 2675);
FORCENOTE
TO SLOT#3
(-1350 6100) 0;
DISPLAY LEFT (-1350 6100);
DISPLAY 1.595745 (-1350 6100);
FORCENOTE
TO OCP NIC
(-1350 5900) 0;
DISPLAY LEFT (-1350 5900);
DISPLAY 1.595745 (-1350 5900);
FORCENOTE
$CDS_IMAGE|12321.jpg|4780|982
(-6800 1525) 0;
DISPLAY LEFT (-6800 1525);
QUIT
